(kicad_sch (version 20230121) (generator eeschema)

  (paper "A3")

  (title_block
    (title "Data Center RDIMM DDR4 Tester")
    (date "2024-09-30")
    (rev "1.2.4")
    (company "Antmicro Ltd.")
    (comment 1 "www.antmicro.com")
    (comment 2 "Antmicro Ltd")
  )

  (junction (at 227.33 248.92) (diameter 0) (color 0 0 0 0)
  )
  (junction (at 343.535 236.22) (diameter 0) (color 0 0 0 0)
  )
  (junction (at 189.23 240.03) (diameter 0) (color 0 0 0 0)
  )
  (junction (at 326.39 236.22) (diameter 0) (color 0 0 0 0)
  )
  (junction (at 281.305 256.54) (diameter 0) (color 0 0 0 0)
  )
  (junction (at 186.055 246.38) (diameter 0) (color 0 0 0 0)
  )
  (junction (at 189.23 248.92) (diameter 0) (color 0 0 0 0)
  )
  (junction (at 74.295 241.3) (diameter 0) (color 0 0 0 0)
  )
  (junction (at 273.05 259.08) (diameter 0) (color 0 0 0 0)
  )
  (junction (at 230.505 240.03) (diameter 0) (color 0 0 0 0)
  )
  (junction (at 186.055 240.03) (diameter 0) (color 0 0 0 0)
  )
  (junction (at 227.33 240.03) (diameter 0) (color 0 0 0 0)
  )
  (junction (at 273.05 242.57) (diameter 0) (color 0 0 0 0)
  )
  (junction (at 281.305 242.57) (diameter 0) (color 0 0 0 0)
  )
  (junction (at 289.56 254) (diameter 0) (color 0 0 0 0)
  )
  (junction (at 336.55 236.22) (diameter 0) (color 0 0 0 0)
  )
  (junction (at 230.505 246.38) (diameter 0) (color 0 0 0 0)
  )
  (junction (at 78.74 241.3) (diameter 0) (color 0 0 0 0)
  )

  (no_connect (at 55.88 163.83))
  (no_connect (at 55.88 138.43))
  (no_connect (at 55.88 151.13))
  (no_connect (at 259.08 133.35))
  (no_connect (at 55.88 115.57))
  (no_connect (at 259.08 110.49))
  (no_connect (at 55.88 143.51))
  (no_connect (at 55.88 140.97))
  (no_connect (at 55.88 189.23))
  (no_connect (at 55.88 130.81))
  (no_connect (at 55.88 146.05))
  (no_connect (at 259.08 95.25))
  (no_connect (at 55.88 92.71))
  (no_connect (at 55.88 72.39))
  (no_connect (at 55.88 166.37))
  (no_connect (at 55.88 95.25))
  (no_connect (at 55.88 74.93))
  (no_connect (at 55.88 153.67))
  (no_connect (at 259.08 107.95))
  (no_connect (at 55.88 82.55))
  (no_connect (at 55.88 90.17))
  (no_connect (at 328.93 189.23))
  (no_connect (at 138.43 189.23))
  (no_connect (at 55.88 64.77))
  (no_connect (at 55.88 120.65))
  (no_connect (at 259.08 74.93))
  (no_connect (at 55.88 135.89))
  (no_connect (at 259.08 72.39))
  (no_connect (at 55.88 85.09))
  (no_connect (at 55.88 161.29))
  (no_connect (at 138.43 64.77))
  (no_connect (at 55.88 67.31))
  (no_connect (at 55.88 77.47))
  (no_connect (at 55.88 156.21))
  (no_connect (at 55.88 107.95))
  (no_connect (at 55.88 118.11))
  (no_connect (at 55.88 158.75))
  (no_connect (at 328.93 64.77))
  (no_connect (at 55.88 69.85))
  (no_connect (at 55.88 133.35))
  (no_connect (at 55.88 87.63))
  (no_connect (at 55.88 80.01))
  (no_connect (at 55.88 148.59))

  (wire (pts (xy 259.08 125.73) (xy 245.745 125.73))
    (stroke (width 0) (type default))
  )
  (wire (pts (xy 127 69.85) (xy 138.43 69.85))
    (stroke (width 0) (type default))
  )
  (wire (pts (xy 379.73 233.045) (xy 376.555 233.045))
    (stroke (width 0) (type default))
  )
  (wire (pts (xy 317.5 97.79) (xy 328.93 97.79))
    (stroke (width 0) (type default))
  )
  (wire (pts (xy 55.88 59.69) (xy 44.45 59.69))
    (stroke (width 0) (type default))
  )
  (wire (pts (xy 245.745 85.09) (xy 250.825 85.09))
    (stroke (width 0) (type default))
  )
  (wire (pts (xy 384.81 233.045) (xy 386.715 233.045))
    (stroke (width 0) (type default))
  )
  (wire (pts (xy 259.08 151.13) (xy 245.745 151.13))
    (stroke (width 0) (type default))
  )
  (polyline (pts (xy 256.54 285.115) (xy 256.54 221.615))
    (stroke (width 0) (type default))
  )

  (wire (pts (xy 317.5 77.47) (xy 328.93 77.47))
    (stroke (width 0) (type default))
  )
  (wire (pts (xy 44.45 110.49) (xy 55.88 110.49))
    (stroke (width 0) (type default))
  )
  (wire (pts (xy 317.5 168.91) (xy 328.93 168.91))
    (stroke (width 0) (type default))
  )
  (wire (pts (xy 127 138.43) (xy 138.43 138.43))
    (stroke (width 0) (type default))
  )
  (wire (pts (xy 317.5 181.61) (xy 328.93 181.61))
    (stroke (width 0) (type default))
  )
  (wire (pts (xy 127 74.93) (xy 138.43 74.93))
    (stroke (width 0) (type default))
  )
  (wire (pts (xy 259.08 173.99) (xy 245.745 173.99))
    (stroke (width 0) (type default))
  )
  (wire (pts (xy 217.17 252.73) (xy 214.63 252.73))
    (stroke (width 0) (type default))
  )
  (wire (pts (xy 195.58 240.03) (xy 189.23 240.03))
    (stroke (width 0) (type default))
  )
  (wire (pts (xy 317.5 146.05) (xy 328.93 146.05))
    (stroke (width 0) (type default))
  )
  (wire (pts (xy 259.08 100.33) (xy 245.745 100.33))
    (stroke (width 0) (type default))
  )
  (wire (pts (xy 127 146.05) (xy 138.43 146.05))
    (stroke (width 0) (type default))
  )
  (wire (pts (xy 317.5 143.51) (xy 328.93 143.51))
    (stroke (width 0) (type default))
  )
  (wire (pts (xy 328.93 67.31) (xy 317.5 67.31))
    (stroke (width 0) (type default))
  )
  (wire (pts (xy 317.5 90.17) (xy 328.93 90.17))
    (stroke (width 0) (type default))
  )
  (wire (pts (xy 388.62 241.3) (xy 388.62 243.205))
    (stroke (width 0) (type default))
  )
  (wire (pts (xy 317.5 153.67) (xy 328.93 153.67))
    (stroke (width 0) (type default))
  )
  (wire (pts (xy 259.08 158.75) (xy 245.745 158.75))
    (stroke (width 0) (type default))
  )
  (wire (pts (xy 336.55 236.22) (xy 343.535 236.22))
    (stroke (width 0) (type default))
  )
  (wire (pts (xy 74.295 243.205) (xy 74.295 241.3))
    (stroke (width 0) (type default))
  )
  (wire (pts (xy 127 143.51) (xy 138.43 143.51))
    (stroke (width 0) (type default))
  )
  (wire (pts (xy 78.74 241.3) (xy 80.645 241.3))
    (stroke (width 0) (type default))
  )
  (polyline (pts (xy 196.85 12.7) (xy 196.85 221.615))
    (stroke (width 0) (type default))
  )

  (wire (pts (xy 55.88 181.61) (xy 44.45 181.61))
    (stroke (width 0) (type default))
  )
  (wire (pts (xy 127 148.59) (xy 138.43 148.59))
    (stroke (width 0) (type default))
  )
  (wire (pts (xy 127 77.47) (xy 138.43 77.47))
    (stroke (width 0) (type default))
  )
  (wire (pts (xy 227.33 248.92) (xy 237.49 248.92))
    (stroke (width 0) (type default))
  )
  (wire (pts (xy 384.81 241.3) (xy 388.62 241.3))
    (stroke (width 0) (type default))
  )
  (wire (pts (xy 80.645 243.84) (xy 78.74 243.84))
    (stroke (width 0) (type default))
  )
  (wire (pts (xy 78.74 243.84) (xy 78.74 241.3))
    (stroke (width 0) (type default))
  )
  (wire (pts (xy 328.93 128.27) (xy 317.5 128.27))
    (stroke (width 0) (type default))
  )
  (wire (pts (xy 127 110.49) (xy 138.43 110.49))
    (stroke (width 0) (type default))
  )
  (wire (pts (xy 269.875 256.54) (xy 281.305 256.54))
    (stroke (width 0) (type default))
  )
  (wire (pts (xy 317.5 113.03) (xy 328.93 113.03))
    (stroke (width 0) (type default))
  )
  (wire (pts (xy 186.055 246.38) (xy 179.07 246.38))
    (stroke (width 0) (type default))
  )
  (wire (pts (xy 127 171.45) (xy 138.43 171.45))
    (stroke (width 0) (type default))
  )
  (wire (pts (xy 259.08 113.03) (xy 245.745 113.03))
    (stroke (width 0) (type default))
  )
  (wire (pts (xy 97.155 241.3) (xy 104.775 241.3))
    (stroke (width 0) (type default))
  )
  (wire (pts (xy 127 107.95) (xy 138.43 107.95))
    (stroke (width 0) (type default))
  )
  (wire (pts (xy 259.08 176.53) (xy 245.745 176.53))
    (stroke (width 0) (type default))
  )
  (wire (pts (xy 195.58 246.38) (xy 186.055 246.38))
    (stroke (width 0) (type default))
  )
  (wire (pts (xy 245.745 161.29) (xy 259.08 161.29))
    (stroke (width 0) (type default))
  )
  (wire (pts (xy 328.93 130.81) (xy 317.5 130.81))
    (stroke (width 0) (type default))
  )
  (wire (pts (xy 259.08 77.47) (xy 245.745 77.47))
    (stroke (width 0) (type default))
  )
  (wire (pts (xy 259.08 115.57) (xy 245.745 115.57))
    (stroke (width 0) (type default))
  )
  (wire (pts (xy 127 179.07) (xy 138.43 179.07))
    (stroke (width 0) (type default))
  )
  (wire (pts (xy 127 158.75) (xy 138.43 158.75))
    (stroke (width 0) (type default))
  )
  (wire (pts (xy 328.93 59.69) (xy 317.5 59.69))
    (stroke (width 0) (type default))
  )
  (wire (pts (xy 317.5 107.95) (xy 328.93 107.95))
    (stroke (width 0) (type default))
  )
  (polyline (pts (xy 300.355 253.365) (xy 300.355 221.615))
    (stroke (width 0) (type default))
  )

  (wire (pts (xy 259.08 102.87) (xy 245.745 102.87))
    (stroke (width 0) (type default))
  )
  (wire (pts (xy 317.5 125.73) (xy 328.93 125.73))
    (stroke (width 0) (type default))
  )
  (wire (pts (xy 55.88 184.15) (xy 44.45 184.15))
    (stroke (width 0) (type default))
  )
  (wire (pts (xy 234.315 266.7) (xy 236.22 266.7))
    (stroke (width 0) (type default))
  )
  (wire (pts (xy 44.45 113.03) (xy 55.88 113.03))
    (stroke (width 0) (type default))
  )
  (wire (pts (xy 222.885 266.7) (xy 222.885 269.24))
    (stroke (width 0) (type default))
  )
  (wire (pts (xy 127 72.39) (xy 138.43 72.39))
    (stroke (width 0) (type default))
  )
  (wire (pts (xy 245.745 153.67) (xy 259.08 153.67))
    (stroke (width 0) (type default))
  )
  (wire (pts (xy 259.08 168.91) (xy 245.745 168.91))
    (stroke (width 0) (type default))
  )
  (wire (pts (xy 127 140.97) (xy 138.43 140.97))
    (stroke (width 0) (type default))
  )
  (wire (pts (xy 127 82.55) (xy 138.43 82.55))
    (stroke (width 0) (type default))
  )
  (wire (pts (xy 317.5 95.25) (xy 328.93 95.25))
    (stroke (width 0) (type default))
  )
  (wire (pts (xy 336.55 236.22) (xy 336.55 238.76))
    (stroke (width 0) (type default))
  )
  (wire (pts (xy 328.93 138.43) (xy 317.5 138.43))
    (stroke (width 0) (type default))
  )
  (wire (pts (xy 317.5 100.33) (xy 328.93 100.33))
    (stroke (width 0) (type default))
  )
  (wire (pts (xy 259.08 140.97) (xy 245.745 140.97))
    (stroke (width 0) (type default))
  )
  (wire (pts (xy 44.45 128.27) (xy 55.88 128.27))
    (stroke (width 0) (type default))
  )
  (wire (pts (xy 317.5 74.93) (xy 328.93 74.93))
    (stroke (width 0) (type default))
  )
  (wire (pts (xy 328.93 120.65) (xy 317.5 120.65))
    (stroke (width 0) (type default))
  )
  (wire (pts (xy 44.45 97.79) (xy 55.88 97.79))
    (stroke (width 0) (type default))
  )
  (wire (pts (xy 127 135.89) (xy 138.43 135.89))
    (stroke (width 0) (type default))
  )
  (wire (pts (xy 127 92.71) (xy 138.43 92.71))
    (stroke (width 0) (type default))
  )
  (wire (pts (xy 259.08 186.69) (xy 245.745 186.69))
    (stroke (width 0) (type default))
  )
  (wire (pts (xy 220.345 266.7) (xy 222.885 266.7))
    (stroke (width 0) (type default))
  )
  (wire (pts (xy 328.93 163.83) (xy 317.5 163.83))
    (stroke (width 0) (type default))
  )
  (wire (pts (xy 328.93 166.37) (xy 317.5 166.37))
    (stroke (width 0) (type default))
  )
  (wire (pts (xy 55.88 173.99) (xy 44.45 173.99))
    (stroke (width 0) (type default))
  )
  (wire (pts (xy 328.93 158.75) (xy 317.5 158.75))
    (stroke (width 0) (type default))
  )
  (wire (pts (xy 127 113.03) (xy 138.43 113.03))
    (stroke (width 0) (type default))
  )
  (wire (pts (xy 127 90.17) (xy 138.43 90.17))
    (stroke (width 0) (type default))
  )
  (wire (pts (xy 289.56 242.57) (xy 281.305 242.57))
    (stroke (width 0) (type default))
  )
  (wire (pts (xy 323.85 227.33) (xy 326.39 227.33))
    (stroke (width 0) (type default))
  )
  (wire (pts (xy 328.93 69.85) (xy 317.5 69.85))
    (stroke (width 0) (type default))
  )
  (wire (pts (xy 259.08 64.77) (xy 245.745 64.77))
    (stroke (width 0) (type default))
  )
  (polyline (pts (xy 162.56 285.115) (xy 162.56 221.615))
    (stroke (width 0) (type default))
  )

  (wire (pts (xy 317.5 184.15) (xy 328.93 184.15))
    (stroke (width 0) (type default))
  )
  (wire (pts (xy 127 156.21) (xy 138.43 156.21))
    (stroke (width 0) (type default))
  )
  (wire (pts (xy 259.08 59.69) (xy 245.745 59.69))
    (stroke (width 0) (type default))
  )
  (wire (pts (xy 127 95.25) (xy 138.43 95.25))
    (stroke (width 0) (type default))
  )
  (wire (pts (xy 55.88 186.69) (xy 44.45 186.69))
    (stroke (width 0) (type default))
  )
  (wire (pts (xy 328.93 85.09) (xy 317.5 85.09))
    (stroke (width 0) (type default))
  )
  (wire (pts (xy 259.08 135.89) (xy 245.745 135.89))
    (stroke (width 0) (type default))
  )
  (wire (pts (xy 127 67.31) (xy 138.43 67.31))
    (stroke (width 0) (type default))
  )
  (wire (pts (xy 273.05 242.57) (xy 270.51 242.57))
    (stroke (width 0) (type default))
  )
  (wire (pts (xy 127 173.99) (xy 138.43 173.99))
    (stroke (width 0) (type default))
  )
  (wire (pts (xy 245.745 146.05) (xy 259.08 146.05))
    (stroke (width 0) (type default))
  )
  (wire (pts (xy 289.56 254) (xy 289.56 261.62))
    (stroke (width 0) (type default))
  )
  (wire (pts (xy 317.5 80.01) (xy 328.93 80.01))
    (stroke (width 0) (type default))
  )
  (wire (pts (xy 189.23 240.03) (xy 189.23 240.665))
    (stroke (width 0) (type default))
  )
  (wire (pts (xy 281.305 256.54) (xy 281.305 252.73))
    (stroke (width 0) (type default))
  )
  (wire (pts (xy 259.08 148.59) (xy 245.745 148.59))
    (stroke (width 0) (type default))
  )
  (wire (pts (xy 44.45 123.19) (xy 55.88 123.19))
    (stroke (width 0) (type default))
  )
  (wire (pts (xy 44.45 105.41) (xy 55.88 105.41))
    (stroke (width 0) (type default))
  )
  (wire (pts (xy 230.505 246.38) (xy 237.49 246.38))
    (stroke (width 0) (type default))
  )
  (wire (pts (xy 317.5 148.59) (xy 328.93 148.59))
    (stroke (width 0) (type default))
  )
  (wire (pts (xy 376.555 241.3) (xy 379.73 241.3))
    (stroke (width 0) (type default))
  )
  (wire (pts (xy 259.08 171.45) (xy 245.745 171.45))
    (stroke (width 0) (type default))
  )
  (wire (pts (xy 186.055 246.38) (xy 186.055 245.745))
    (stroke (width 0) (type default))
  )
  (wire (pts (xy 317.5 156.21) (xy 328.93 156.21))
    (stroke (width 0) (type default))
  )
  (wire (pts (xy 186.055 240.03) (xy 189.23 240.03))
    (stroke (width 0) (type default))
  )
  (wire (pts (xy 127 130.81) (xy 138.43 130.81))
    (stroke (width 0) (type default))
  )
  (wire (pts (xy 343.535 236.22) (xy 352.425 236.22))
    (stroke (width 0) (type default))
  )
  (wire (pts (xy 230.505 240.665) (xy 230.505 240.03))
    (stroke (width 0) (type default))
  )
  (wire (pts (xy 127 85.09) (xy 138.43 85.09))
    (stroke (width 0) (type default))
  )
  (wire (pts (xy 259.08 118.11) (xy 245.745 118.11))
    (stroke (width 0) (type default))
  )
  (wire (pts (xy 183.515 268.605) (xy 185.42 268.605))
    (stroke (width 0) (type default))
  )
  (wire (pts (xy 317.5 110.49) (xy 328.93 110.49))
    (stroke (width 0) (type default))
  )
  (wire (pts (xy 214.63 240.03) (xy 227.33 240.03))
    (stroke (width 0) (type default))
  )
  (wire (pts (xy 259.08 138.43) (xy 245.745 138.43))
    (stroke (width 0) (type default))
  )
  (wire (pts (xy 127 123.19) (xy 138.43 123.19))
    (stroke (width 0) (type default))
  )
  (wire (pts (xy 44.45 102.87) (xy 55.88 102.87))
    (stroke (width 0) (type default))
  )
  (wire (pts (xy 259.08 163.83) (xy 245.745 163.83))
    (stroke (width 0) (type default))
  )
  (wire (pts (xy 343.535 236.22) (xy 343.535 238.76))
    (stroke (width 0) (type default))
  )
  (wire (pts (xy 328.93 118.11) (xy 317.5 118.11))
    (stroke (width 0) (type default))
  )
  (wire (pts (xy 189.23 248.92) (xy 179.07 248.92))
    (stroke (width 0) (type default))
  )
  (wire (pts (xy 273.05 259.08) (xy 273.05 261.62))
    (stroke (width 0) (type default))
  )
  (wire (pts (xy 259.08 82.55) (xy 245.745 82.55))
    (stroke (width 0) (type default))
  )
  (wire (pts (xy 127 125.73) (xy 138.43 125.73))
    (stroke (width 0) (type default))
  )
  (wire (pts (xy 230.505 245.745) (xy 230.505 246.38))
    (stroke (width 0) (type default))
  )
  (wire (pts (xy 245.745 92.71) (xy 259.08 92.71))
    (stroke (width 0) (type default))
  )
  (wire (pts (xy 97.155 243.84) (xy 99.695 243.84))
    (stroke (width 0) (type default))
  )
  (wire (pts (xy 55.88 171.45) (xy 44.45 171.45))
    (stroke (width 0) (type default))
  )
  (wire (pts (xy 317.5 179.07) (xy 328.93 179.07))
    (stroke (width 0) (type default))
  )
  (wire (pts (xy 328.93 161.29) (xy 317.5 161.29))
    (stroke (width 0) (type default))
  )
  (wire (pts (xy 317.5 102.87) (xy 328.93 102.87))
    (stroke (width 0) (type default))
  )
  (wire (pts (xy 317.5 186.69) (xy 328.93 186.69))
    (stroke (width 0) (type default))
  )
  (wire (pts (xy 259.08 179.07) (xy 245.745 179.07))
    (stroke (width 0) (type default))
  )
  (wire (pts (xy 189.23 248.92) (xy 195.58 248.92))
    (stroke (width 0) (type default))
  )
  (wire (pts (xy 186.055 240.03) (xy 179.07 240.03))
    (stroke (width 0) (type default))
  )
  (wire (pts (xy 186.055 240.665) (xy 186.055 240.03))
    (stroke (width 0) (type default))
  )
  (wire (pts (xy 127 100.33) (xy 138.43 100.33))
    (stroke (width 0) (type default))
  )
  (wire (pts (xy 289.56 247.65) (xy 289.56 242.57))
    (stroke (width 0) (type default))
  )
  (wire (pts (xy 127 115.57) (xy 138.43 115.57))
    (stroke (width 0) (type default))
  )
  (wire (pts (xy 326.39 236.22) (xy 336.55 236.22))
    (stroke (width 0) (type default))
  )
  (wire (pts (xy 326.39 236.22) (xy 326.39 238.76))
    (stroke (width 0) (type default))
  )
  (wire (pts (xy 55.88 176.53) (xy 44.45 176.53))
    (stroke (width 0) (type default))
  )
  (wire (pts (xy 127 80.01) (xy 138.43 80.01))
    (stroke (width 0) (type default))
  )
  (wire (pts (xy 74.295 241.3) (xy 78.74 241.3))
    (stroke (width 0) (type default))
  )
  (wire (pts (xy 317.5 133.35) (xy 328.93 133.35))
    (stroke (width 0) (type default))
  )
  (wire (pts (xy 99.695 243.84) (xy 99.695 248.285))
    (stroke (width 0) (type default))
  )
  (wire (pts (xy 189.23 248.92) (xy 189.23 245.745))
    (stroke (width 0) (type default))
  )
  (wire (pts (xy 227.33 245.745) (xy 227.33 248.92))
    (stroke (width 0) (type default))
  )
  (wire (pts (xy 227.33 240.03) (xy 230.505 240.03))
    (stroke (width 0) (type default))
  )
  (wire (pts (xy 259.08 123.19) (xy 245.745 123.19))
    (stroke (width 0) (type default))
  )
  (wire (pts (xy 281.305 242.57) (xy 273.05 242.57))
    (stroke (width 0) (type default))
  )
  (wire (pts (xy 281.305 247.65) (xy 281.305 242.57))
    (stroke (width 0) (type default))
  )
  (wire (pts (xy 127 184.15) (xy 138.43 184.15))
    (stroke (width 0) (type default))
  )
  (wire (pts (xy 317.5 171.45) (xy 328.93 171.45))
    (stroke (width 0) (type default))
  )
  (wire (pts (xy 259.08 97.79) (xy 245.745 97.79))
    (stroke (width 0) (type default))
  )
  (wire (pts (xy 214.63 248.92) (xy 227.33 248.92))
    (stroke (width 0) (type default))
  )
  (wire (pts (xy 245.745 128.27) (xy 259.08 128.27))
    (stroke (width 0) (type default))
  )
  (wire (pts (xy 178.435 268.605) (xy 176.53 268.605))
    (stroke (width 0) (type default))
  )
  (wire (pts (xy 269.875 259.08) (xy 273.05 259.08))
    (stroke (width 0) (type default))
  )
  (wire (pts (xy 289.56 254) (xy 289.56 252.73))
    (stroke (width 0) (type default))
  )
  (wire (pts (xy 127 105.41) (xy 138.43 105.41))
    (stroke (width 0) (type default))
  )
  (wire (pts (xy 317.5 135.89) (xy 328.93 135.89))
    (stroke (width 0) (type default))
  )
  (wire (pts (xy 55.88 179.07) (xy 44.45 179.07))
    (stroke (width 0) (type default))
  )
  (wire (pts (xy 127 102.87) (xy 138.43 102.87))
    (stroke (width 0) (type default))
  )
  (wire (pts (xy 127 87.63) (xy 138.43 87.63))
    (stroke (width 0) (type default))
  )
  (wire (pts (xy 245.745 67.31) (xy 259.08 67.31))
    (stroke (width 0) (type default))
  )
  (wire (pts (xy 127 166.37) (xy 138.43 166.37))
    (stroke (width 0) (type default))
  )
  (wire (pts (xy 259.08 143.51) (xy 245.745 143.51))
    (stroke (width 0) (type default))
  )
  (wire (pts (xy 44.45 125.73) (xy 55.88 125.73))
    (stroke (width 0) (type default))
  )
  (wire (pts (xy 127 176.53) (xy 138.43 176.53))
    (stroke (width 0) (type default))
  )
  (wire (pts (xy 127 133.35) (xy 138.43 133.35))
    (stroke (width 0) (type default))
  )
  (wire (pts (xy 317.5 151.13) (xy 328.93 151.13))
    (stroke (width 0) (type default))
  )
  (wire (pts (xy 328.93 173.99) (xy 317.5 173.99))
    (stroke (width 0) (type default))
  )
  (wire (pts (xy 326.39 227.33) (xy 326.39 228.6))
    (stroke (width 0) (type default))
  )
  (wire (pts (xy 245.745 80.01) (xy 259.08 80.01))
    (stroke (width 0) (type default))
  )
  (wire (pts (xy 227.33 240.665) (xy 227.33 240.03))
    (stroke (width 0) (type default))
  )
  (wire (pts (xy 127 120.65) (xy 138.43 120.65))
    (stroke (width 0) (type default))
  )
  (wire (pts (xy 317.5 123.19) (xy 328.93 123.19))
    (stroke (width 0) (type default))
  )
  (wire (pts (xy 281.305 256.54) (xy 281.305 261.62))
    (stroke (width 0) (type default))
  )
  (wire (pts (xy 214.63 246.38) (xy 230.505 246.38))
    (stroke (width 0) (type default))
  )
  (wire (pts (xy 127 151.13) (xy 138.43 151.13))
    (stroke (width 0) (type default))
  )
  (wire (pts (xy 328.93 176.53) (xy 317.5 176.53))
    (stroke (width 0) (type default))
  )
  (wire (pts (xy 317.5 115.57) (xy 328.93 115.57))
    (stroke (width 0) (type default))
  )
  (wire (pts (xy 245.745 181.61) (xy 259.08 181.61))
    (stroke (width 0) (type default))
  )
  (wire (pts (xy 127 168.91) (xy 138.43 168.91))
    (stroke (width 0) (type default))
  )
  (wire (pts (xy 138.43 59.69) (xy 127 59.69))
    (stroke (width 0) (type default))
  )
  (wire (pts (xy 127 181.61) (xy 138.43 181.61))
    (stroke (width 0) (type default))
  )
  (wire (pts (xy 127 97.79) (xy 138.43 97.79))
    (stroke (width 0) (type default))
  )
  (wire (pts (xy 55.88 168.91) (xy 44.45 168.91))
    (stroke (width 0) (type default))
  )
  (wire (pts (xy 328.93 82.55) (xy 317.5 82.55))
    (stroke (width 0) (type default))
  )
  (wire (pts (xy 326.39 233.68) (xy 326.39 236.22))
    (stroke (width 0) (type default))
  )
  (wire (pts (xy 259.08 69.85) (xy 245.745 69.85))
    (stroke (width 0) (type default))
  )
  (wire (pts (xy 245.745 87.63) (xy 259.08 87.63))
    (stroke (width 0) (type default))
  )
  (wire (pts (xy 317.5 72.39) (xy 328.93 72.39))
    (stroke (width 0) (type default))
  )
  (wire (pts (xy 217.17 252.73) (xy 217.17 254.635))
    (stroke (width 0) (type default))
  )
  (wire (pts (xy 245.745 189.23) (xy 259.08 189.23))
    (stroke (width 0) (type default))
  )
  (wire (pts (xy 259.08 130.81) (xy 245.745 130.81))
    (stroke (width 0) (type default))
  )
  (wire (pts (xy 74.295 241.3) (xy 69.215 241.3))
    (stroke (width 0) (type default))
  )
  (wire (pts (xy 317.5 92.71) (xy 328.93 92.71))
    (stroke (width 0) (type default))
  )
  (wire (pts (xy 259.08 85.09) (xy 255.905 85.09))
    (stroke (width 0) (type default))
  )
  (wire (pts (xy 269.875 254) (xy 289.56 254))
    (stroke (width 0) (type default))
  )
  (wire (pts (xy 44.45 100.33) (xy 55.88 100.33))
    (stroke (width 0) (type default))
  )
  (wire (pts (xy 236.22 266.7) (xy 236.22 269.24))
    (stroke (width 0) (type default))
  )
  (wire (pts (xy 245.745 184.15) (xy 259.08 184.15))
    (stroke (width 0) (type default))
  )
  (wire (pts (xy 328.93 140.97) (xy 317.5 140.97))
    (stroke (width 0) (type default))
  )
  (wire (pts (xy 273.05 259.08) (xy 273.05 252.73))
    (stroke (width 0) (type default))
  )
  (wire (pts (xy 127 128.27) (xy 138.43 128.27))
    (stroke (width 0) (type default))
  )
  (wire (pts (xy 317.5 105.41) (xy 328.93 105.41))
    (stroke (width 0) (type default))
  )
  (wire (pts (xy 259.08 120.65) (xy 245.745 120.65))
    (stroke (width 0) (type default))
  )
  (polyline (pts (xy 12.7 221.615) (xy 407.67 221.615))
    (stroke (width 0) (type default))
  )

  (wire (pts (xy 127 153.67) (xy 138.43 153.67))
    (stroke (width 0) (type default))
  )
  (wire (pts (xy 317.5 87.63) (xy 328.93 87.63))
    (stroke (width 0) (type default))
  )
  (wire (pts (xy 259.08 166.37) (xy 245.745 166.37))
    (stroke (width 0) (type default))
  )
  (wire (pts (xy 127 161.29) (xy 138.43 161.29))
    (stroke (width 0) (type default))
  )
  (wire (pts (xy 127 186.69) (xy 138.43 186.69))
    (stroke (width 0) (type default))
  )
  (wire (pts (xy 273.05 242.57) (xy 273.05 247.65))
    (stroke (width 0) (type default))
  )
  (wire (pts (xy 259.08 156.21) (xy 245.745 156.21))
    (stroke (width 0) (type default))
  )
  (wire (pts (xy 127 163.83) (xy 138.43 163.83))
    (stroke (width 0) (type default))
  )
  (wire (pts (xy 259.08 105.41) (xy 245.745 105.41))
    (stroke (width 0) (type default))
  )
  (wire (pts (xy 230.505 240.03) (xy 237.49 240.03))
    (stroke (width 0) (type default))
  )
  (wire (pts (xy 259.08 90.17) (xy 245.745 90.17))
    (stroke (width 0) (type default))
  )
  (wire (pts (xy 127 118.11) (xy 138.43 118.11))
    (stroke (width 0) (type default))
  )

  (text "Serial adress select" (at 259.08 226.695 0)
    (effects (font (size 2.4892 2.4892) (thickness 0.4978) bold) (justify left bottom))
  )
  (text "BANK 34" (at 339.09 43.18 0)
    (effects (font (size 2.4892 2.4892) (thickness 0.4978) bold) (justify left bottom))
  )
  (text "I2C logic translator" (at 190.5 228.6 0)
    (effects (font (size 2.4892 2.4892) (thickness 0.4978) bold) (justify left bottom))
  )
  (text "BANK 33" (at 265.43 43.815 0)
    (effects (font (size 2.4892 2.4892) (thickness 0.4978) bold) (justify left bottom))
  )
  (text "VCCO (HR banks) max: 3.6V" (at 95.885 50.8 0)
    (effects (font (size 1.27 1.27)) (justify left bottom))
  )
  (text "Open drain pin" (at 173.355 273.05 0)
    (effects (font (size 1.27 1.27)) (justify left bottom))
  )
  (text "VCCO (HP banks) max: 2.0V" (at 295.91 50.8 0)
    (effects (font (size 1.27 1.27)) (justify left bottom))
  )
  (text "BANK 16" (at 68.58 43.18 0)
    (effects (font (size 2.4892 2.4892) (thickness 0.4978) bold) (justify left bottom))
  )
  (text "Clock source" (at 77.47 231.775 0)
    (effects (font (size 2.4892 2.4892) (thickness 0.4978) bold) (justify left bottom))
  )
  (text "Default 000" (at 271.78 229.235 0)
    (effects (font (size 1.27 1.27)) (justify left bottom))
  )
  (text "BANK 32" (at 142.24 42.545 0)
    (effects (font (size 2.4892 2.4892) (thickness 0.4978) bold) (justify left bottom))
  )
  (text "HDMI" (at 26.67 180.975 90)
    (effects (font (size 1.27 1.27)) (justify left bottom))
  )
  (text "VREF" (at 304.165 227.965 0)
    (effects (font (size 2.4892 2.4892) (thickness 0.4978) bold) (justify left bottom))
  )

  (global_label "DQ51" (shape input) (at 127 146.05 180) (fields_autoplaced)
    (effects (font (size 1.27 1.27)) (justify right))
    (property "Intersheetrefs" "${INTERSHEET_REFS}" (at 119.6563 145.9706 0)
      (effects (font (size 1.27 1.27)) (justify right) hide)
    )
  )
  (global_label "TMDS_CLK_P" (shape input) (at 44.45 179.07 180) (fields_autoplaced)
    (effects (font (size 1.27 1.27)) (justify right))
    (property "Intersheetrefs" "${INTERSHEET_REFS}" (at 7.62 -11.43 0)
      (effects (font (size 1.27 1.27)) hide)
    )
  )
  (global_label "PARITY" (shape input) (at 245.745 179.07 180) (fields_autoplaced)
    (effects (font (size 1.27 1.27)) (justify right))
    (property "Intersheetrefs" "${INTERSHEET_REFS}" (at 12.065 -14.605 0)
      (effects (font (size 1.27 1.27)) hide)
    )
  )
  (global_label "VDDQ" (shape input) (at 323.85 227.33 180) (fields_autoplaced)
    (effects (font (size 1.27 1.27)) (justify right))
    (property "Intersheetrefs" "${INTERSHEET_REFS}" (at 91.44 437.515 0)
      (effects (font (size 1.27 1.27)) hide)
    )
  )
  (global_label "~{EVENT}" (shape input) (at 185.42 268.605 0) (fields_autoplaced)
    (effects (font (size 1.27 1.27)) (justify left))
    (property "Intersheetrefs" "${INTERSHEET_REFS}" (at -59.69 573.405 0)
      (effects (font (size 1.27 1.27)) hide)
    )
  )
  (global_label "DQS3_N" (shape input) (at 317.5 171.45 180) (fields_autoplaced)
    (effects (font (size 1.27 1.27)) (justify right))
    (property "Intersheetrefs" "${INTERSHEET_REFS}" (at 307.8582 171.3706 0)
      (effects (font (size 1.27 1.27)) (justify right) hide)
    )
  )
  (global_label "DQ56" (shape input) (at 127 184.15 180) (fields_autoplaced)
    (effects (font (size 1.27 1.27)) (justify right))
    (property "Intersheetrefs" "${INTERSHEET_REFS}" (at 119.6563 184.0706 0)
      (effects (font (size 1.27 1.27)) (justify right) hide)
    )
  )
  (global_label "~{SAVE}" (shape input) (at 245.745 90.17 180) (fields_autoplaced)
    (effects (font (size 1.27 1.27)) (justify right))
    (property "Intersheetrefs" "${INTERSHEET_REFS}" (at 12.065 -14.605 0)
      (effects (font (size 1.27 1.27)) hide)
    )
  )
  (global_label "~{CS0}" (shape input) (at 245.745 92.71 180) (fields_autoplaced)
    (effects (font (size 1.27 1.27)) (justify right))
    (property "Intersheetrefs" "${INTERSHEET_REFS}" (at 239.7318 92.7894 0)
      (effects (font (size 1.27 1.27)) (justify right) hide)
    )
  )
  (global_label "SD_DAT1" (shape input) (at 44.45 100.33 180) (fields_autoplaced)
    (effects (font (size 1.27 1.27)) (justify right))
    (property "Intersheetrefs" "${INTERSHEET_REFS}" (at -1.27 -11.43 0)
      (effects (font (size 1.27 1.27)) hide)
    )
  )
  (global_label "DQ36" (shape input) (at 127 72.39 180) (fields_autoplaced)
    (effects (font (size 1.27 1.27)) (justify right))
    (property "Intersheetrefs" "${INTERSHEET_REFS}" (at 119.6563 72.3106 0)
      (effects (font (size 1.27 1.27)) (justify right) hide)
    )
  )
  (global_label "~{ALERT}" (shape input) (at 245.745 166.37 180) (fields_autoplaced)
    (effects (font (size 1.27 1.27)) (justify right))
    (property "Intersheetrefs" "${INTERSHEET_REFS}" (at 12.065 -14.605 0)
      (effects (font (size 1.27 1.27)) hide)
    )
  )
  (global_label "CK1_P" (shape input) (at 245.745 138.43 180) (fields_autoplaced)
    (effects (font (size 1.27 1.27)) (justify right))
    (property "Intersheetrefs" "${INTERSHEET_REFS}" (at 12.065 -14.605 0)
      (effects (font (size 1.27 1.27)) hide)
    )
  )
  (global_label "DQ54" (shape input) (at 127 153.67 180) (fields_autoplaced)
    (effects (font (size 1.27 1.27)) (justify right))
    (property "Intersheetrefs" "${INTERSHEET_REFS}" (at 119.6563 153.5906 0)
      (effects (font (size 1.27 1.27)) (justify right) hide)
    )
  )
  (global_label "DQ46" (shape input) (at 127 148.59 180) (fields_autoplaced)
    (effects (font (size 1.27 1.27)) (justify right))
    (property "Intersheetrefs" "${INTERSHEET_REFS}" (at 119.6563 148.5106 0)
      (effects (font (size 1.27 1.27)) (justify right) hide)
    )
  )
  (global_label "DQ37" (shape input) (at 127 105.41 180) (fields_autoplaced)
    (effects (font (size 1.27 1.27)) (justify right))
    (property "Intersheetrefs" "${INTERSHEET_REFS}" (at 119.6563 105.3306 0)
      (effects (font (size 1.27 1.27)) (justify right) hide)
    )
  )
  (global_label "DQ57" (shape input) (at 127 110.49 180) (fields_autoplaced)
    (effects (font (size 1.27 1.27)) (justify right))
    (property "Intersheetrefs" "${INTERSHEET_REFS}" (at 119.6563 110.4106 0)
      (effects (font (size 1.27 1.27)) (justify right) hide)
    )
  )
  (global_label "DQS1_N" (shape input) (at 317.5 125.73 180) (fields_autoplaced)
    (effects (font (size 1.27 1.27)) (justify right))
    (property "Intersheetrefs" "${INTERSHEET_REFS}" (at 307.8582 125.6506 0)
      (effects (font (size 1.27 1.27)) (justify right) hide)
    )
  )
  (global_label "NC\\C2" (shape input) (at 245.745 77.47 180) (fields_autoplaced)
    (effects (font (size 1.27 1.27)) (justify right))
    (property "Intersheetrefs" "${INTERSHEET_REFS}" (at 411.48 194.31 0)
      (effects (font (size 1.27 1.27)) hide)
    )
  )
  (global_label "3V3_SYS" (shape input) (at 69.215 241.3 180) (fields_autoplaced)
    (effects (font (size 1.27 1.27)) (justify right))
    (property "Intersheetrefs" "${INTERSHEET_REFS}" (at -168.91 318.77 0)
      (effects (font (size 1.27 1.27)) hide)
    )
  )
  (global_label "DQ59" (shape input) (at 127 181.61 180) (fields_autoplaced)
    (effects (font (size 1.27 1.27)) (justify right))
    (property "Intersheetrefs" "${INTERSHEET_REFS}" (at 119.6563 181.5306 0)
      (effects (font (size 1.27 1.27)) (justify right) hide)
    )
  )
  (global_label "DQS2_N" (shape input) (at 317.5 110.49 180) (fields_autoplaced)
    (effects (font (size 1.27 1.27)) (justify right))
    (property "Intersheetrefs" "${INTERSHEET_REFS}" (at 307.8582 110.4106 0)
      (effects (font (size 1.27 1.27)) (justify right) hide)
    )
  )
  (global_label "DQ7" (shape input) (at 317.5 140.97 180) (fields_autoplaced)
    (effects (font (size 1.27 1.27)) (justify right))
    (property "Intersheetrefs" "${INTERSHEET_REFS}" (at 311.3658 140.8906 0)
      (effects (font (size 1.27 1.27)) (justify right) hide)
    )
  )
  (global_label "TMDS_D2_N" (shape input) (at 44.45 176.53 180) (fields_autoplaced)
    (effects (font (size 1.27 1.27)) (justify right))
    (property "Intersheetrefs" "${INTERSHEET_REFS}" (at 13.335 -11.43 0)
      (effects (font (size 1.27 1.27)) hide)
    )
  )
  (global_label "SD_DAT3" (shape input) (at 44.45 102.87 180) (fields_autoplaced)
    (effects (font (size 1.27 1.27)) (justify right))
    (property "Intersheetrefs" "${INTERSHEET_REFS}" (at -1.27 -11.43 0)
      (effects (font (size 1.27 1.27)) hide)
    )
  )
  (global_label "SDA_3V3" (shape input) (at 179.07 248.92 180) (fields_autoplaced)
    (effects (font (size 1.27 1.27)) (justify right))
    (property "Intersheetrefs" "${INTERSHEET_REFS}" (at -148.59 3.81 0)
      (effects (font (size 1.27 1.27)) hide)
    )
  )
  (global_label "VDDSPD" (shape input) (at 237.49 240.03 0) (fields_autoplaced)
    (effects (font (size 1.27 1.27)) (justify left))
    (property "Intersheetrefs" "${INTERSHEET_REFS}" (at -142.875 12.065 0)
      (effects (font (size 1.27 1.27)) hide)
    )
  )
  (global_label "A0" (shape input) (at 245.745 184.15 180) (fields_autoplaced)
    (effects (font (size 1.27 1.27)) (justify right))
    (property "Intersheetrefs" "${INTERSHEET_REFS}" (at 12.065 -14.605 0)
      (effects (font (size 1.27 1.27)) hide)
    )
  )
  (global_label "VDDQ" (shape input) (at 317.5 59.69 180) (fields_autoplaced)
    (effects (font (size 1.27 1.27)) (justify right))
    (property "Intersheetrefs" "${INTERSHEET_REFS}" (at 267.97 407.035 0)
      (effects (font (size 1.27 1.27)) hide)
    )
  )
  (global_label "VDDQ" (shape input) (at 386.715 233.045 0) (fields_autoplaced)
    (effects (font (size 1.27 1.27)) (justify left))
    (property "Intersheetrefs" "${INTERSHEET_REFS}" (at 154.305 -33.655 0)
      (effects (font (size 1.27 1.27)) hide)
    )
  )
  (global_label "DQS13_N" (shape input) (at 127 85.09 180) (fields_autoplaced)
    (effects (font (size 1.27 1.27)) (justify right))
    (property "Intersheetrefs" "${INTERSHEET_REFS}" (at 116.1487 85.0106 0)
      (effects (font (size 1.27 1.27)) (justify right) hide)
    )
  )
  (global_label "DQS7_N" (shape input) (at 127 166.37 180) (fields_autoplaced)
    (effects (font (size 1.27 1.27)) (justify right))
    (property "Intersheetrefs" "${INTERSHEET_REFS}" (at 117.3582 166.2906 0)
      (effects (font (size 1.27 1.27)) (justify right) hide)
    )
  )
  (global_label "DQ62" (shape input) (at 127 168.91 180) (fields_autoplaced)
    (effects (font (size 1.27 1.27)) (justify right))
    (property "Intersheetrefs" "${INTERSHEET_REFS}" (at 119.6563 168.8306 0)
      (effects (font (size 1.27 1.27)) (justify right) hide)
    )
  )
  (global_label "A10\\AP" (shape input) (at 245.745 156.21 180) (fields_autoplaced)
    (effects (font (size 1.27 1.27)) (justify right))
    (property "Intersheetrefs" "${INTERSHEET_REFS}" (at 12.065 -14.605 0)
      (effects (font (size 1.27 1.27)) hide)
    )
  )
  (global_label "SA1" (shape input) (at 269.875 256.54 180) (fields_autoplaced)
    (effects (font (size 1.27 1.27)) (justify right))
    (property "Intersheetrefs" "${INTERSHEET_REFS}" (at 2.54 -3.81 0)
      (effects (font (size 1.27 1.27)) hide)
    )
  )
  (global_label "CKE0" (shape input) (at 245.745 102.87 180) (fields_autoplaced)
    (effects (font (size 1.27 1.27)) (justify right))
    (property "Intersheetrefs" "${INTERSHEET_REFS}" (at 12.065 -14.605 0)
      (effects (font (size 1.27 1.27)) hide)
    )
  )
  (global_label "TMDS_D0_N" (shape input) (at 44.45 171.45 180) (fields_autoplaced)
    (effects (font (size 1.27 1.27)) (justify right))
    (property "Intersheetrefs" "${INTERSHEET_REFS}" (at 7.62 -11.43 0)
      (effects (font (size 1.27 1.27)) hide)
    )
  )
  (global_label "DQ19" (shape input) (at 317.5 166.37 180) (fields_autoplaced)
    (effects (font (size 1.27 1.27)) (justify right))
    (property "Intersheetrefs" "${INTERSHEET_REFS}" (at 310.1563 166.2906 0)
      (effects (font (size 1.27 1.27)) (justify right) hide)
    )
  )
  (global_label "DQ17" (shape input) (at 317.5 100.33 180) (fields_autoplaced)
    (effects (font (size 1.27 1.27)) (justify right))
    (property "Intersheetrefs" "${INTERSHEET_REFS}" (at 310.1563 100.2506 0)
      (effects (font (size 1.27 1.27)) (justify right) hide)
    )
  )
  (global_label "DQS5_P" (shape input) (at 127 128.27 180) (fields_autoplaced)
    (effects (font (size 1.27 1.27)) (justify right))
    (property "Intersheetrefs" "${INTERSHEET_REFS}" (at 117.4187 128.1906 0)
      (effects (font (size 1.27 1.27)) (justify right) hide)
    )
  )
  (global_label "~{RAS}\\A16" (shape input) (at 245.745 146.05 180) (fields_autoplaced)
    (effects (font (size 1.27 1.27)) (justify right))
    (property "Intersheetrefs" "${INTERSHEET_REFS}" (at 12.065 -14.605 0)
      (effects (font (size 1.27 1.27)) hide)
    )
  )
  (global_label "DQS10_N" (shape input) (at 317.5 85.09 180) (fields_autoplaced)
    (effects (font (size 1.27 1.27)) (justify right))
    (property "Intersheetrefs" "${INTERSHEET_REFS}" (at 306.6487 85.0106 0)
      (effects (font (size 1.27 1.27)) (justify right) hide)
    )
  )
  (global_label "A3" (shape input) (at 245.745 163.83 180) (fields_autoplaced)
    (effects (font (size 1.27 1.27)) (justify right))
    (property "Intersheetrefs" "${INTERSHEET_REFS}" (at 12.065 -14.605 0)
      (effects (font (size 1.27 1.27)) hide)
    )
  )
  (global_label "DQ58" (shape input) (at 127 171.45 180) (fields_autoplaced)
    (effects (font (size 1.27 1.27)) (justify right))
    (property "Intersheetrefs" "${INTERSHEET_REFS}" (at 119.6563 171.3706 0)
      (effects (font (size 1.27 1.27)) (justify right) hide)
    )
  )
  (global_label "DQ20" (shape input) (at 317.5 74.93 180) (fields_autoplaced)
    (effects (font (size 1.27 1.27)) (justify right))
    (property "Intersheetrefs" "${INTERSHEET_REFS}" (at 310.1563 74.8506 0)
      (effects (font (size 1.27 1.27)) (justify right) hide)
    )
  )
  (global_label "BG1" (shape input) (at 245.745 186.69 180) (fields_autoplaced)
    (effects (font (size 1.27 1.27)) (justify right))
    (property "Intersheetrefs" "${INTERSHEET_REFS}" (at 12.065 -14.605 0)
      (effects (font (size 1.27 1.27)) hide)
    )
  )
  (global_label "DQ45" (shape input) (at 127 92.71 180) (fields_autoplaced)
    (effects (font (size 1.27 1.27)) (justify right))
    (property "Intersheetrefs" "${INTERSHEET_REFS}" (at 119.6563 92.6306 0)
      (effects (font (size 1.27 1.27)) (justify right) hide)
    )
  )
  (global_label "TMDS_D0_P" (shape input) (at 44.45 168.91 180) (fields_autoplaced)
    (effects (font (size 1.27 1.27)) (justify right))
    (property "Intersheetrefs" "${INTERSHEET_REFS}" (at 7.62 -11.43 0)
      (effects (font (size 1.27 1.27)) hide)
    )
  )
  (global_label "DQ34" (shape input) (at 127 87.63 180) (fields_autoplaced)
    (effects (font (size 1.27 1.27)) (justify right))
    (property "Intersheetrefs" "${INTERSHEET_REFS}" (at 119.6563 87.5506 0)
      (effects (font (size 1.27 1.27)) (justify right) hide)
    )
  )
  (global_label "A11" (shape input) (at 245.745 113.03 180) (fields_autoplaced)
    (effects (font (size 1.27 1.27)) (justify right))
    (property "Intersheetrefs" "${INTERSHEET_REFS}" (at 12.065 -17.145 0)
      (effects (font (size 1.27 1.27)) hide)
    )
  )
  (global_label "A17" (shape input) (at 245.745 148.59 180) (fields_autoplaced)
    (effects (font (size 1.27 1.27)) (justify right))
    (property "Intersheetrefs" "${INTERSHEET_REFS}" (at 12.065 -14.605 0)
      (effects (font (size 1.27 1.27)) hide)
    )
  )
  (global_label "DQ25" (shape input) (at 317.5 184.15 180) (fields_autoplaced)
    (effects (font (size 1.27 1.27)) (justify right))
    (property "Intersheetrefs" "${INTERSHEET_REFS}" (at 310.1563 184.0706 0)
      (effects (font (size 1.27 1.27)) (justify right) hide)
    )
  )
  (global_label "A2" (shape input) (at 245.745 158.75 180) (fields_autoplaced)
    (effects (font (size 1.27 1.27)) (justify right))
    (property "Intersheetrefs" "${INTERSHEET_REFS}" (at 12.065 -14.605 0)
      (effects (font (size 1.27 1.27)) hide)
    )
  )
  (global_label "DQ27" (shape input) (at 317.5 153.67 180) (fields_autoplaced)
    (effects (font (size 1.27 1.27)) (justify right))
    (property "Intersheetrefs" "${INTERSHEET_REFS}" (at 310.1563 153.5906 0)
      (effects (font (size 1.27 1.27)) (justify right) hide)
    )
  )
  (global_label "~{CS3}\\C1,NC" (shape input) (at 245.745 69.85 180) (fields_autoplaced)
    (effects (font (size 1.27 1.27)) (justify right))
    (property "Intersheetrefs" "${INTERSHEET_REFS}" (at 411.48 156.21 0)
      (effects (font (size 1.27 1.27)) hide)
    )
  )
  (global_label "DQ21" (shape input) (at 317.5 102.87 180) (fields_autoplaced)
    (effects (font (size 1.27 1.27)) (justify right))
    (property "Intersheetrefs" "${INTERSHEET_REFS}" (at 310.1563 102.7906 0)
      (effects (font (size 1.27 1.27)) (justify right) hide)
    )
  )
  (global_label "DQ16" (shape input) (at 317.5 105.41 180) (fields_autoplaced)
    (effects (font (size 1.27 1.27)) (justify right))
    (property "Intersheetrefs" "${INTERSHEET_REFS}" (at 310.1563 105.3306 0)
      (effects (font (size 1.27 1.27)) (justify right) hide)
    )
  )
  (global_label "DQ61" (shape input) (at 127 107.95 180) (fields_autoplaced)
    (effects (font (size 1.27 1.27)) (justify right))
    (property "Intersheetrefs" "${INTERSHEET_REFS}" (at 119.6563 107.8706 0)
      (effects (font (size 1.27 1.27)) (justify right) hide)
    )
  )
  (global_label "DQ30" (shape input) (at 317.5 181.61 180) (fields_autoplaced)
    (effects (font (size 1.27 1.27)) (justify right))
    (property "Intersheetrefs" "${INTERSHEET_REFS}" (at 310.1563 181.5306 0)
      (effects (font (size 1.27 1.27)) (justify right) hide)
    )
  )
  (global_label "DQS13_P" (shape input) (at 127 82.55 180) (fields_autoplaced)
    (effects (font (size 1.27 1.27)) (justify right))
    (property "Intersheetrefs" "${INTERSHEET_REFS}" (at 116.2091 82.4706 0)
      (effects (font (size 1.27 1.27)) (justify right) hide)
    )
  )
  (global_label "DQ39" (shape input) (at 127 77.47 180) (fields_autoplaced)
    (effects (font (size 1.27 1.27)) (justify right))
    (property "Intersheetrefs" "${INTERSHEET_REFS}" (at 119.6563 77.3906 0)
      (effects (font (size 1.27 1.27)) (justify right) hide)
    )
  )
  (global_label "SD_DAT0" (shape input) (at 44.45 123.19 180) (fields_autoplaced)
    (effects (font (size 1.27 1.27)) (justify right))
    (property "Intersheetrefs" "${INTERSHEET_REFS}" (at -1.27 -11.43 0)
      (effects (font (size 1.27 1.27)) hide)
    )
  )
  (global_label "A9" (shape input) (at 245.745 97.79 180) (fields_autoplaced)
    (effects (font (size 1.27 1.27)) (justify right))
    (property "Intersheetrefs" "${INTERSHEET_REFS}" (at 12.065 -14.605 0)
      (effects (font (size 1.27 1.27)) hide)
    )
  )
  (global_label "DQ33" (shape input) (at 127 95.25 180) (fields_autoplaced)
    (effects (font (size 1.27 1.27)) (justify right))
    (property "Intersheetrefs" "${INTERSHEET_REFS}" (at 119.6563 95.1706 0)
      (effects (font (size 1.27 1.27)) (justify right) hide)
    )
  )
  (global_label "DQ40" (shape input) (at 127 113.03 180) (fields_autoplaced)
    (effects (font (size 1.27 1.27)) (justify right))
    (property "Intersheetrefs" "${INTERSHEET_REFS}" (at 119.6563 112.9506 0)
      (effects (font (size 1.27 1.27)) (justify right) hide)
    )
  )
  (global_label "DQ5" (shape input) (at 317.5 67.31 180) (fields_autoplaced)
    (effects (font (size 1.27 1.27)) (justify right))
    (property "Intersheetrefs" "${INTERSHEET_REFS}" (at 311.3658 67.2306 0)
      (effects (font (size 1.27 1.27)) (justify right) hide)
    )
  )
  (global_label "~{PERST}" (shape input) (at 44.45 110.49 180) (fields_autoplaced)
    (effects (font (size 1.27 1.27)) (justify right))
    (property "Intersheetrefs" "${INTERSHEET_REFS}" (at 36.2596 110.4106 0)
      (effects (font (size 1.27 1.27)) (justify right) hide)
    )
  )
  (global_label "3V3_SYS" (shape input) (at 44.45 59.69 180) (fields_autoplaced)
    (effects (font (size 1.27 1.27)) (justify right))
    (property "Intersheetrefs" "${INTERSHEET_REFS}" (at -1.905 134.62 0)
      (effects (font (size 1.27 1.27)) hide)
    )
  )
  (global_label "DQ63" (shape input) (at 127 179.07 180) (fields_autoplaced)
    (effects (font (size 1.27 1.27)) (justify right))
    (property "Intersheetrefs" "${INTERSHEET_REFS}" (at 119.6563 178.9906 0)
      (effects (font (size 1.27 1.27)) (justify right) hide)
    )
  )
  (global_label "DQS16_P" (shape input) (at 127 173.99 180) (fields_autoplaced)
    (effects (font (size 1.27 1.27)) (justify right))
    (property "Intersheetrefs" "${INTERSHEET_REFS}" (at 116.2091 173.9106 0)
      (effects (font (size 1.27 1.27)) (justify right) hide)
    )
  )
  (global_label "DQ60" (shape input) (at 127 186.69 180) (fields_autoplaced)
    (effects (font (size 1.27 1.27)) (justify right))
    (property "Intersheetrefs" "${INTERSHEET_REFS}" (at 119.6563 186.6106 0)
      (effects (font (size 1.27 1.27)) (justify right) hide)
    )
  )
  (global_label "DQ55" (shape input) (at 127 156.21 180) (fields_autoplaced)
    (effects (font (size 1.27 1.27)) (justify right))
    (property "Intersheetrefs" "${INTERSHEET_REFS}" (at 119.6563 156.1306 0)
      (effects (font (size 1.27 1.27)) (justify right) hide)
    )
  )
  (global_label "DQS4_N" (shape input) (at 127 69.85 180) (fields_autoplaced)
    (effects (font (size 1.27 1.27)) (justify right))
    (property "Intersheetrefs" "${INTERSHEET_REFS}" (at 292.735 -82.55 0)
      (effects (font (size 1.27 1.27)) (justify left) hide)
    )
  )
  (global_label "3V3_SYS" (shape input) (at 179.07 240.03 180) (fields_autoplaced)
    (effects (font (size 1.27 1.27)) (justify right))
    (property "Intersheetrefs" "${INTERSHEET_REFS}" (at -148.59 0 0)
      (effects (font (size 1.27 1.27)) hide)
    )
  )
  (global_label "A5" (shape input) (at 245.745 125.73 180) (fields_autoplaced)
    (effects (font (size 1.27 1.27)) (justify right))
    (property "Intersheetrefs" "${INTERSHEET_REFS}" (at 12.065 -14.605 0)
      (effects (font (size 1.27 1.27)) hide)
    )
  )
  (global_label "DQ10" (shape input) (at 317.5 135.89 180) (fields_autoplaced)
    (effects (font (size 1.27 1.27)) (justify right))
    (property "Intersheetrefs" "${INTERSHEET_REFS}" (at 310.1563 135.8106 0)
      (effects (font (size 1.27 1.27)) (justify right) hide)
    )
  )
  (global_label "DQS0_N" (shape input) (at 317.5 151.13 180) (fields_autoplaced)
    (effects (font (size 1.27 1.27)) (justify right))
    (property "Intersheetrefs" "${INTERSHEET_REFS}" (at 307.8582 151.0506 0)
      (effects (font (size 1.27 1.27)) (justify right) hide)
    )
  )
  (global_label "SD_CLK" (shape input) (at 44.45 125.73 180) (fields_autoplaced)
    (effects (font (size 1.27 1.27)) (justify right))
    (property "Intersheetrefs" "${INTERSHEET_REFS}" (at -1.27 -11.43 0)
      (effects (font (size 1.27 1.27)) hide)
    )
  )
  (global_label "VDDQ" (shape input) (at 245.745 59.69 180) (fields_autoplaced)
    (effects (font (size 1.27 1.27)) (justify right))
    (property "Intersheetrefs" "${INTERSHEET_REFS}" (at 196.215 338.455 0)
      (effects (font (size 1.27 1.27)) hide)
    )
  )
  (global_label "DQ1" (shape input) (at 317.5 90.17 180) (fields_autoplaced)
    (effects (font (size 1.27 1.27)) (justify right))
    (property "Intersheetrefs" "${INTERSHEET_REFS}" (at 311.3658 90.0906 0)
      (effects (font (size 1.27 1.27)) (justify right) hide)
    )
  )
  (global_label "DQ24" (shape input) (at 317.5 173.99 180) (fields_autoplaced)
    (effects (font (size 1.27 1.27)) (justify right))
    (property "Intersheetrefs" "${INTERSHEET_REFS}" (at 310.1563 173.9106 0)
      (effects (font (size 1.27 1.27)) (justify right) hide)
    )
  )
  (global_label "CKE1\\NC" (shape input) (at 245.745 105.41 180) (fields_autoplaced)
    (effects (font (size 1.27 1.27)) (justify right))
    (property "Intersheetrefs" "${INTERSHEET_REFS}" (at 17.78 -14.605 0)
      (effects (font (size 1.27 1.27)) hide)
    )
  )
  (global_label "DQ32" (shape input) (at 127 74.93 180) (fields_autoplaced)
    (effects (font (size 1.27 1.27)) (justify right))
    (property "Intersheetrefs" "${INTERSHEET_REFS}" (at 119.6563 74.8506 0)
      (effects (font (size 1.27 1.27)) (justify right) hide)
    )
  )
  (global_label "DQ50" (shape input) (at 127 143.51 180) (fields_autoplaced)
    (effects (font (size 1.27 1.27)) (justify right))
    (property "Intersheetrefs" "${INTERSHEET_REFS}" (at 119.6563 143.4306 0)
      (effects (font (size 1.27 1.27)) (justify right) hide)
    )
  )
  (global_label "DQS12_N" (shape input) (at 317.5 161.29 180) (fields_autoplaced)
    (effects (font (size 1.27 1.27)) (justify right))
    (property "Intersheetrefs" "${INTERSHEET_REFS}" (at 306.6487 161.2106 0)
      (effects (font (size 1.27 1.27)) (justify right) hide)
    )
  )
  (global_label "~{RESET}" (shape input) (at 245.745 176.53 180) (fields_autoplaced)
    (effects (font (size 1.27 1.27)) (justify right))
    (property "Intersheetrefs" "${INTERSHEET_REFS}" (at 617.855 334.645 0)
      (effects (font (size 1.27 1.27)) hide)
    )
  )
  (global_label "SD_CMD" (shape input) (at 44.45 105.41 180) (fields_autoplaced)
    (effects (font (size 1.27 1.27)) (justify right))
    (property "Intersheetrefs" "${INTERSHEET_REFS}" (at -1.27 -11.43 0)
      (effects (font (size 1.27 1.27)) hide)
    )
  )
  (global_label "DQS11_N" (shape input) (at 317.5 115.57 180) (fields_autoplaced)
    (effects (font (size 1.27 1.27)) (justify right))
    (property "Intersheetrefs" "${INTERSHEET_REFS}" (at 306.6487 115.4906 0)
      (effects (font (size 1.27 1.27)) (justify right) hide)
    )
  )
  (global_label "DQS2_P" (shape input) (at 317.5 107.95 180) (fields_autoplaced)
    (effects (font (size 1.27 1.27)) (justify right))
    (property "Intersheetrefs" "${INTERSHEET_REFS}" (at 307.9187 107.8706 0)
      (effects (font (size 1.27 1.27)) (justify right) hide)
    )
  )
  (global_label "DQ31" (shape input) (at 317.5 179.07 180) (fields_autoplaced)
    (effects (font (size 1.27 1.27)) (justify right))
    (property "Intersheetrefs" "${INTERSHEET_REFS}" (at 310.1563 178.9906 0)
      (effects (font (size 1.27 1.27)) (justify right) hide)
    )
  )
  (global_label "3V3_SYS" (shape input) (at 220.345 266.7 180) (fields_autoplaced)
    (effects (font (size 1.27 1.27)) (justify right))
    (property "Intersheetrefs" "${INTERSHEET_REFS}" (at -15.24 581.66 0)
      (effects (font (size 1.27 1.27)) hide)
    )
  )
  (global_label "CK0_N" (shape input) (at 245.745 171.45 180) (fields_autoplaced)
    (effects (font (size 1.27 1.27)) (justify right))
    (property "Intersheetrefs" "${INTERSHEET_REFS}" (at 12.065 -14.605 0)
      (effects (font (size 1.27 1.27)) hide)
    )
  )
  (global_label "DQS3_P" (shape input) (at 317.5 168.91 180) (fields_autoplaced)
    (effects (font (size 1.27 1.27)) (justify right))
    (property "Intersheetrefs" "${INTERSHEET_REFS}" (at 307.9187 168.8306 0)
      (effects (font (size 1.27 1.27)) (justify right) hide)
    )
  )
  (global_label "TMDS_D1_P" (shape input) (at 44.45 184.15 180) (fields_autoplaced)
    (effects (font (size 1.27 1.27)) (justify right))
    (property "Intersheetrefs" "${INTERSHEET_REFS}" (at 12.065 -11.43 0)
      (effects (font (size 1.27 1.27)) hide)
    )
  )
  (global_label "A12\\~{BC}" (shape input) (at 245.745 115.57 180) (fields_autoplaced)
    (effects (font (size 1.27 1.27)) (justify right))
    (property "Intersheetrefs" "${INTERSHEET_REFS}" (at 12.065 -12.065 0)
      (effects (font (size 1.27 1.27)) hide)
    )
  )
  (global_label "A8" (shape input) (at 245.745 173.99 180) (fields_autoplaced)
    (effects (font (size 1.27 1.27)) (justify right))
    (property "Intersheetrefs" "${INTERSHEET_REFS}" (at 12.065 -14.605 0)
      (effects (font (size 1.27 1.27)) hide)
    )
  )
  (global_label "VRP" (shape input) (at 245.745 189.23 180) (fields_autoplaced)
    (effects (font (size 1.27 1.27)) (justify right))
    (property "Intersheetrefs" "${INTERSHEET_REFS}" (at 12.065 -14.605 0)
      (effects (font (size 1.27 1.27)) hide)
    )
  )
  (global_label "DQ12" (shape input) (at 317.5 95.25 180) (fields_autoplaced)
    (effects (font (size 1.27 1.27)) (justify right))
    (property "Intersheetrefs" "${INTERSHEET_REFS}" (at 310.1563 95.1706 0)
      (effects (font (size 1.27 1.27)) (justify right) hide)
    )
  )
  (global_label "A1" (shape input) (at 245.745 130.81 180) (fields_autoplaced)
    (effects (font (size 1.27 1.27)) (justify right))
    (property "Intersheetrefs" "${INTERSHEET_REFS}" (at 12.065 -14.605 0)
      (effects (font (size 1.27 1.27)) hide)
    )
  )
  (global_label "VREF_33" (shape input) (at 352.425 236.22 0) (fields_autoplaced)
    (effects (font (size 1.27 1.27)) (justify left))
    (property "Intersheetrefs" "${INTERSHEET_REFS}" (at 116.205 -6.35 0)
      (effects (font (size 1.27 1.27)) hide)
    )
  )
  (global_label "VDDSPD" (shape input) (at 270.51 242.57 180) (fields_autoplaced)
    (effects (font (size 1.27 1.27)) (justify right))
    (property "Intersheetrefs" "${INTERSHEET_REFS}" (at 29.845 529.59 0)
      (effects (font (size 1.27 1.27)) hide)
    )
  )
  (global_label "DQ48" (shape input) (at 127 100.33 180) (fields_autoplaced)
    (effects (font (size 1.27 1.27)) (justify right))
    (property "Intersheetrefs" "${INTERSHEET_REFS}" (at 119.6563 100.2506 0)
      (effects (font (size 1.27 1.27)) (justify right) hide)
    )
  )
  (global_label "SD_DAT2" (shape input) (at 44.45 113.03 180) (fields_autoplaced)
    (effects (font (size 1.27 1.27)) (justify right))
    (property "Intersheetrefs" "${INTERSHEET_REFS}" (at -1.27 -11.43 0)
      (effects (font (size 1.27 1.27)) hide)
    )
  )
  (global_label "DQ26" (shape input) (at 317.5 156.21 180) (fields_autoplaced)
    (effects (font (size 1.27 1.27)) (justify right))
    (property "Intersheetrefs" "${INTERSHEET_REFS}" (at 310.1563 156.1306 0)
      (effects (font (size 1.27 1.27)) (justify right) hide)
    )
  )
  (global_label "ODT0" (shape input) (at 245.745 153.67 180) (fields_autoplaced)
    (effects (font (size 1.27 1.27)) (justify right))
    (property "Intersheetrefs" "${INTERSHEET_REFS}" (at 12.065 -14.605 0)
      (effects (font (size 1.27 1.27)) hide)
    )
  )
  (global_label "CK0_P" (shape input) (at 245.745 168.91 180) (fields_autoplaced)
    (effects (font (size 1.27 1.27)) (justify right))
    (property "Intersheetrefs" "${INTERSHEET_REFS}" (at 12.065 -14.605 0)
      (effects (font (size 1.27 1.27)) hide)
    )
  )
  (global_label "A13" (shape input) (at 245.745 151.13 180) (fields_autoplaced)
    (effects (font (size 1.27 1.27)) (justify right))
    (property "Intersheetrefs" "${INTERSHEET_REFS}" (at 12.065 -14.605 0)
      (effects (font (size 1.27 1.27)) hide)
    )
  )
  (global_label "A7" (shape input) (at 245.745 100.33 180) (fields_autoplaced)
    (effects (font (size 1.27 1.27)) (justify right))
    (property "Intersheetrefs" "${INTERSHEET_REFS}" (at 12.065 -14.605 0)
      (effects (font (size 1.27 1.27)) hide)
    )
  )
  (global_label "DQS5_N" (shape input) (at 127 130.81 180) (fields_autoplaced)
    (effects (font (size 1.27 1.27)) (justify right))
    (property "Intersheetrefs" "${INTERSHEET_REFS}" (at 117.3582 130.7306 0)
      (effects (font (size 1.27 1.27)) (justify right) hide)
    )
  )
  (global_label "DQ3" (shape input) (at 317.5 146.05 180) (fields_autoplaced)
    (effects (font (size 1.27 1.27)) (justify right))
    (property "Intersheetrefs" "${INTERSHEET_REFS}" (at 311.3658 145.9706 0)
      (effects (font (size 1.27 1.27)) (justify right) hide)
    )
  )
  (global_label "DQ47" (shape input) (at 127 135.89 180) (fields_autoplaced)
    (effects (font (size 1.27 1.27)) (justify right))
    (property "Intersheetrefs" "${INTERSHEET_REFS}" (at 119.6563 135.8106 0)
      (effects (font (size 1.27 1.27)) (justify right) hide)
    )
  )
  (global_label "VDDQ" (shape input) (at 127 59.69 180) (fields_autoplaced)
    (effects (font (size 1.27 1.27)) (justify right))
    (property "Intersheetrefs" "${INTERSHEET_REFS}" (at 80.645 200.66 0)
      (effects (font (size 1.27 1.27)) hide)
    )
  )
  (global_label "VREF_33" (shape input) (at 245.745 161.29 180) (fields_autoplaced)
    (effects (font (size 1.27 1.27)) (justify right))
    (property "Intersheetrefs" "${INTERSHEET_REFS}" (at 12.065 -14.605 0)
      (effects (font (size 1.27 1.27)) hide)
    )
  )
  (global_label "BA0" (shape input) (at 245.745 128.27 180) (fields_autoplaced)
    (effects (font (size 1.27 1.27)) (justify right))
    (property "Intersheetrefs" "${INTERSHEET_REFS}" (at 12.065 -14.605 0)
      (effects (font (size 1.27 1.27)) hide)
    )
  )
  (global_label "DQ14" (shape input) (at 317.5 128.27 180) (fields_autoplaced)
    (effects (font (size 1.27 1.27)) (justify right))
    (property "Intersheetrefs" "${INTERSHEET_REFS}" (at 310.1563 128.1906 0)
      (effects (font (size 1.27 1.27)) (justify right) hide)
    )
  )
  (global_label "VDDSPD" (shape input) (at 234.315 266.7 180) (fields_autoplaced)
    (effects (font (size 1.27 1.27)) (justify right))
    (property "Intersheetrefs" "${INTERSHEET_REFS}" (at -1.27 662.305 0)
      (effects (font (size 1.27 1.27)) hide)
    )
  )
  (global_label "DQS7_P" (shape input) (at 127 163.83 180) (fields_autoplaced)
    (effects (font (size 1.27 1.27)) (justify right))
    (property "Intersheetrefs" "${INTERSHEET_REFS}" (at 117.4187 163.7506 0)
      (effects (font (size 1.27 1.27)) (justify right) hide)
    )
  )
  (global_label "DQ18" (shape input) (at 317.5 120.65 180) (fields_autoplaced)
    (effects (font (size 1.27 1.27)) (justify right))
    (property "Intersheetrefs" "${INTERSHEET_REFS}" (at 310.1563 120.5706 0)
      (effects (font (size 1.27 1.27)) (justify right) hide)
    )
  )
  (global_label "SCL_2V5" (shape input) (at 237.49 246.38 0) (fields_autoplaced)
    (effects (font (size 1.27 1.27)) (justify left))
    (property "Intersheetrefs" "${INTERSHEET_REFS}" (at -137.795 3.81 0)
      (effects (font (size 1.27 1.27)) hide)
    )
  )
  (global_label "VDDQ" (shape input) (at 176.53 268.605 180) (fields_autoplaced)
    (effects (font (size 1.27 1.27)) (justify right))
    (property "Intersheetrefs" "${INTERSHEET_REFS}" (at -52.705 573.405 0)
      (effects (font (size 1.27 1.27)) hide)
    )
  )
  (global_label "CK1_N" (shape input) (at 245.745 140.97 180) (fields_autoplaced)
    (effects (font (size 1.27 1.27)) (justify right))
    (property "Intersheetrefs" "${INTERSHEET_REFS}" (at 12.065 -14.605 0)
      (effects (font (size 1.27 1.27)) hide)
    )
  )
  (global_label "SDA_2V5" (shape input) (at 237.49 248.92 0) (fields_autoplaced)
    (effects (font (size 1.27 1.27)) (justify left))
    (property "Intersheetrefs" "${INTERSHEET_REFS}" (at -137.795 3.81 0)
      (effects (font (size 1.27 1.27)) hide)
    )
  )
  (global_label "DQ38" (shape input) (at 127 80.01 180) (fields_autoplaced)
    (effects (font (size 1.27 1.27)) (justify right))
    (property "Intersheetrefs" "${INTERSHEET_REFS}" (at 119.6563 79.9306 0)
      (effects (font (size 1.27 1.27)) (justify right) hide)
    )
  )
  (global_label "DQ9" (shape input) (at 317.5 97.79 180) (fields_autoplaced)
    (effects (font (size 1.27 1.27)) (justify right))
    (property "Intersheetrefs" "${INTERSHEET_REFS}" (at 311.3658 97.7106 0)
      (effects (font (size 1.27 1.27)) (justify right) hide)
    )
  )
  (global_label "~{WE}\\A14" (shape input) (at 245.745 143.51 180) (fields_autoplaced)
    (effects (font (size 1.27 1.27)) (justify right))
    (property "Intersheetrefs" "${INTERSHEET_REFS}" (at 12.065 -14.605 0)
      (effects (font (size 1.27 1.27)) hide)
    )
  )
  (global_label "DQ35" (shape input) (at 127 90.17 180) (fields_autoplaced)
    (effects (font (size 1.27 1.27)) (justify right))
    (property "Intersheetrefs" "${INTERSHEET_REFS}" (at 119.6563 90.0906 0)
      (effects (font (size 1.27 1.27)) (justify right) hide)
    )
  )
  (global_label "DQ22" (shape input) (at 317.5 118.11 180) (fields_autoplaced)
    (effects (font (size 1.27 1.27)) (justify right))
    (property "Intersheetrefs" "${INTERSHEET_REFS}" (at 310.1563 118.0306 0)
      (effects (font (size 1.27 1.27)) (justify right) hide)
    )
  )
  (global_label "VRN" (shape input) (at 376.555 233.045 180) (fields_autoplaced)
    (effects (font (size 1.27 1.27)) (justify right))
    (property "Intersheetrefs" "${INTERSHEET_REFS}" (at 160.02 -33.655 0)
      (effects (font (size 1.27 1.27)) hide)
    )
  )
  (global_label "TMDS_D1_N" (shape input) (at 44.45 186.69 180) (fields_autoplaced)
    (effects (font (size 1.27 1.27)) (justify right))
    (property "Intersheetrefs" "${INTERSHEET_REFS}" (at 12.065 -11.43 0)
      (effects (font (size 1.27 1.27)) hide)
    )
  )
  (global_label "~{CS1}\\NC" (shape input) (at 245.745 87.63 180) (fields_autoplaced)
    (effects (font (size 1.27 1.27)) (justify right))
    (property "Intersheetrefs" "${INTERSHEET_REFS}" (at 411.48 196.85 0)
      (effects (font (size 1.27 1.27)) hide)
    )
  )
  (global_label "DQS14_P" (shape input) (at 127 138.43 180) (fields_autoplaced)
    (effects (font (size 1.27 1.27)) (justify right))
    (property "Intersheetrefs" "${INTERSHEET_REFS}" (at 116.2091 138.3506 0)
      (effects (font (size 1.27 1.27)) (justify right) hide)
    )
  )
  (global_label "SCL_3V3" (shape input) (at 179.07 246.38 180) (fields_autoplaced)
    (effects (font (size 1.27 1.27)) (justify right))
    (property "Intersheetrefs" "${INTERSHEET_REFS}" (at -148.59 3.81 0)
      (effects (font (size 1.27 1.27)) hide)
    )
  )
  (global_label "BA1" (shape input) (at 245.745 135.89 180) (fields_autoplaced)
    (effects (font (size 1.27 1.27)) (justify right))
    (property "Intersheetrefs" "${INTERSHEET_REFS}" (at 12.065 -14.605 0)
      (effects (font (size 1.27 1.27)) hide)
    )
  )
  (global_label "~{CAS}\\A15" (shape input) (at 245.745 181.61 180) (fields_autoplaced)
    (effects (font (size 1.27 1.27)) (justify right))
    (property "Intersheetrefs" "${INTERSHEET_REFS}" (at 12.065 -14.605 0)
      (effects (font (size 1.27 1.27)) hide)
    )
  )
  (global_label "DQS0_P" (shape input) (at 317.5 148.59 180) (fields_autoplaced)
    (effects (font (size 1.27 1.27)) (justify right))
    (property "Intersheetrefs" "${INTERSHEET_REFS}" (at 307.9187 148.5106 0)
      (effects (font (size 1.27 1.27)) (justify right) hide)
    )
  )
  (global_label "DQ15" (shape input) (at 317.5 130.81 180) (fields_autoplaced)
    (effects (font (size 1.27 1.27)) (justify right))
    (property "Intersheetrefs" "${INTERSHEET_REFS}" (at 310.1563 130.7306 0)
      (effects (font (size 1.27 1.27)) (justify right) hide)
    )
  )
  (global_label "TMDS_CLK_N" (shape input) (at 44.45 181.61 180) (fields_autoplaced)
    (effects (font (size 1.27 1.27)) (justify right))
    (property "Intersheetrefs" "${INTERSHEET_REFS}" (at 7.62 -11.43 0)
      (effects (font (size 1.27 1.27)) hide)
    )
  )
  (global_label "DQS14_N" (shape input) (at 127 140.97 180) (fields_autoplaced)
    (effects (font (size 1.27 1.27)) (justify right))
    (property "Intersheetrefs" "${INTERSHEET_REFS}" (at 116.1487 140.8906 0)
      (effects (font (size 1.27 1.27)) (justify right) hide)
    )
  )
  (global_label "DQS6_N" (shape input) (at 127 161.29 180) (fields_autoplaced)
    (effects (font (size 1.27 1.27)) (justify right))
    (property "Intersheetrefs" "${INTERSHEET_REFS}" (at 292.735 -21.59 0)
      (effects (font (size 1.27 1.27)) (justify left) hide)
    )
  )
  (global_label "DQS4_P" (shape input) (at 127 67.31 180) (fields_autoplaced)
    (effects (font (size 1.27 1.27)) (justify right))
    (property "Intersheetrefs" "${INTERSHEET_REFS}" (at 292.735 -82.55 0)
      (effects (font (size 1.27 1.27)) (justify left) hide)
    )
  )
  (global_label "DQ29" (shape input) (at 317.5 186.69 180) (fields_autoplaced)
    (effects (font (size 1.27 1.27)) (justify right))
    (property "Intersheetrefs" "${INTERSHEET_REFS}" (at 310.1563 186.6106 0)
      (effects (font (size 1.27 1.27)) (justify right) hide)
    )
  )
  (global_label "DQS12_P" (shape input) (at 317.5 158.75 180) (fields_autoplaced)
    (effects (font (size 1.27 1.27)) (justify right))
    (property "Intersheetrefs" "${INTERSHEET_REFS}" (at 306.7091 158.6706 0)
      (effects (font (size 1.27 1.27)) (justify right) hide)
    )
  )
  (global_label "~{ACT}" (shape input) (at 245.745 82.55 180) (fields_autoplaced)
    (effects (font (size 1.27 1.27)) (justify right))
    (property "Intersheetrefs" "${INTERSHEET_REFS}" (at 12.065 -14.605 0)
      (effects (font (size 1.27 1.27)) hide)
    )
  )
  (global_label "GCLK100" (shape input) (at 44.45 128.27 180) (fields_autoplaced)
    (effects (font (size 1.27 1.27)) (justify right))
    (property "Intersheetrefs" "${INTERSHEET_REFS}" (at -1.27 -11.43 0)
      (effects (font (size 1.27 1.27)) hide)
    )
  )
  (global_label "DQ49" (shape input) (at 127 133.35 180) (fields_autoplaced)
    (effects (font (size 1.27 1.27)) (justify right))
    (property "Intersheetrefs" "${INTERSHEET_REFS}" (at 119.6563 133.2706 0)
      (effects (font (size 1.27 1.27)) (justify right) hide)
    )
  )
  (global_label "DQS9_N" (shape input) (at 317.5 80.01 180) (fields_autoplaced)
    (effects (font (size 1.27 1.27)) (justify right))
    (property "Intersheetrefs" "${INTERSHEET_REFS}" (at 307.8582 79.9306 0)
      (effects (font (size 1.27 1.27)) (justify right) hide)
    )
  )
  (global_label "SA2" (shape input) (at 269.875 259.08 180) (fields_autoplaced)
    (effects (font (size 1.27 1.27)) (justify right))
    (property "Intersheetrefs" "${INTERSHEET_REFS}" (at 2.54 -3.81 0)
      (effects (font (size 1.27 1.27)) hide)
    )
  )
  (global_label "DQS11_P" (shape input) (at 317.5 113.03 180) (fields_autoplaced)
    (effects (font (size 1.27 1.27)) (justify right))
    (property "Intersheetrefs" "${INTERSHEET_REFS}" (at 306.7091 112.9506 0)
      (effects (font (size 1.27 1.27)) (justify right) hide)
    )
  )
  (global_label "SD_CD" (shape input) (at 44.45 97.79 180) (fields_autoplaced)
    (effects (font (size 1.27 1.27)) (justify right))
    (property "Intersheetrefs" "${INTERSHEET_REFS}" (at -1.27 -11.43 0)
      (effects (font (size 1.27 1.27)) hide)
    )
  )
  (global_label "DQ13" (shape input) (at 317.5 92.71 180) (fields_autoplaced)
    (effects (font (size 1.27 1.27)) (justify right))
    (property "Intersheetrefs" "${INTERSHEET_REFS}" (at 310.1563 92.6306 0)
      (effects (font (size 1.27 1.27)) (justify right) hide)
    )
  )
  (global_label "GCLK100" (shape input) (at 104.775 241.3 0) (fields_autoplaced)
    (effects (font (size 1.27 1.27)) (justify left))
    (property "Intersheetrefs" "${INTERSHEET_REFS}" (at 41.91 -13.97 0)
      (effects (font (size 1.27 1.27)) hide)
    )
  )
  (global_label "DQ6" (shape input) (at 317.5 138.43 180) (fields_autoplaced)
    (effects (font (size 1.27 1.27)) (justify right))
    (property "Intersheetrefs" "${INTERSHEET_REFS}" (at 311.3658 138.3506 0)
      (effects (font (size 1.27 1.27)) (justify right) hide)
    )
  )
  (global_label "DQS16_N" (shape input) (at 127 176.53 180) (fields_autoplaced)
    (effects (font (size 1.27 1.27)) (justify right))
    (property "Intersheetrefs" "${INTERSHEET_REFS}" (at 116.1487 176.4506 0)
      (effects (font (size 1.27 1.27)) (justify right) hide)
    )
  )
  (global_label "DQ11" (shape input) (at 317.5 133.35 180) (fields_autoplaced)
    (effects (font (size 1.27 1.27)) (justify right))
    (property "Intersheetrefs" "${INTERSHEET_REFS}" (at 310.1563 133.2706 0)
      (effects (font (size 1.27 1.27)) (justify right) hide)
    )
  )
  (global_label "DQ2" (shape input) (at 317.5 143.51 180) (fields_autoplaced)
    (effects (font (size 1.27 1.27)) (justify right))
    (property "Intersheetrefs" "${INTERSHEET_REFS}" (at 311.3658 143.4306 0)
      (effects (font (size 1.27 1.27)) (justify right) hide)
    )
  )
  (global_label "~{CS2}\\C0" (shape input) (at 245.745 67.31 180) (fields_autoplaced)
    (effects (font (size 1.27 1.27)) (justify right))
    (property "Intersheetrefs" "${INTERSHEET_REFS}" (at 411.48 181.61 0)
      (effects (font (size 1.27 1.27)) hide)
    )
  )
  (global_label "DQ8" (shape input) (at 317.5 72.39 180) (fields_autoplaced)
    (effects (font (size 1.27 1.27)) (justify right))
    (property "Intersheetrefs" "${INTERSHEET_REFS}" (at 311.3658 72.3106 0)
      (effects (font (size 1.27 1.27)) (justify right) hide)
    )
  )
  (global_label "DQ28" (shape input) (at 317.5 176.53 180) (fields_autoplaced)
    (effects (font (size 1.27 1.27)) (justify right))
    (property "Intersheetrefs" "${INTERSHEET_REFS}" (at 310.1563 176.4506 0)
      (effects (font (size 1.27 1.27)) (justify right) hide)
    )
  )
  (global_label "DQ0" (shape input) (at 317.5 69.85 180) (fields_autoplaced)
    (effects (font (size 1.27 1.27)) (justify right))
    (property "Intersheetrefs" "${INTERSHEET_REFS}" (at 311.3658 69.7706 0)
      (effects (font (size 1.27 1.27)) (justify right) hide)
    )
  )
  (global_label "DQS9_P" (shape input) (at 317.5 77.47 180) (fields_autoplaced)
    (effects (font (size 1.27 1.27)) (justify right))
    (property "Intersheetrefs" "${INTERSHEET_REFS}" (at 307.9187 77.3906 0)
      (effects (font (size 1.27 1.27)) (justify right) hide)
    )
  )
  (global_label "TMDS_D2_P" (shape input) (at 44.45 173.99 180) (fields_autoplaced)
    (effects (font (size 1.27 1.27)) (justify right))
    (property "Intersheetrefs" "${INTERSHEET_REFS}" (at 13.335 -11.43 0)
      (effects (font (size 1.27 1.27)) hide)
    )
  )
  (global_label "DQ52" (shape input) (at 127 97.79 180) (fields_autoplaced)
    (effects (font (size 1.27 1.27)) (justify right))
    (property "Intersheetrefs" "${INTERSHEET_REFS}" (at 119.6563 97.7106 0)
      (effects (font (size 1.27 1.27)) (justify right) hide)
    )
  )
  (global_label "BG0" (shape input) (at 245.745 118.11 180) (fields_autoplaced)
    (effects (font (size 1.27 1.27)) (justify right))
    (property "Intersheetrefs" "${INTERSHEET_REFS}" (at 12.065 -14.605 0)
      (effects (font (size 1.27 1.27)) hide)
    )
  )
  (global_label "DQS6_P" (shape input) (at 127 158.75 180) (fields_autoplaced)
    (effects (font (size 1.27 1.27)) (justify right))
    (property "Intersheetrefs" "${INTERSHEET_REFS}" (at 292.735 -21.59 0)
      (effects (font (size 1.27 1.27)) (justify left) hide)
    )
  )
  (global_label "DQS10_P" (shape input) (at 317.5 82.55 180) (fields_autoplaced)
    (effects (font (size 1.27 1.27)) (justify right))
    (property "Intersheetrefs" "${INTERSHEET_REFS}" (at 306.7091 82.4706 0)
      (effects (font (size 1.27 1.27)) (justify right) hide)
    )
  )
  (global_label "DQ42" (shape input) (at 127 125.73 180) (fields_autoplaced)
    (effects (font (size 1.27 1.27)) (justify right))
    (property "Intersheetrefs" "${INTERSHEET_REFS}" (at 119.6563 125.6506 0)
      (effects (font (size 1.27 1.27)) (justify right) hide)
    )
  )
  (global_label "DQS15_P" (shape input) (at 127 118.11 180) (fields_autoplaced)
    (effects (font (size 1.27 1.27)) (justify right))
    (property "Intersheetrefs" "${INTERSHEET_REFS}" (at 116.2091 118.0306 0)
      (effects (font (size 1.27 1.27)) (justify right) hide)
    )
  )
  (global_label "DQ23" (shape input) (at 317.5 163.83 180) (fields_autoplaced)
    (effects (font (size 1.27 1.27)) (justify right))
    (property "Intersheetrefs" "${INTERSHEET_REFS}" (at 310.1563 163.7506 0)
      (effects (font (size 1.27 1.27)) (justify right) hide)
    )
  )
  (global_label "DQ43" (shape input) (at 127 115.57 180) (fields_autoplaced)
    (effects (font (size 1.27 1.27)) (justify right))
    (property "Intersheetrefs" "${INTERSHEET_REFS}" (at 119.6563 115.4906 0)
      (effects (font (size 1.27 1.27)) (justify right) hide)
    )
  )
  (global_label "SA0" (shape input) (at 269.875 254 180) (fields_autoplaced)
    (effects (font (size 1.27 1.27)) (justify right))
    (property "Intersheetrefs" "${INTERSHEET_REFS}" (at 2.54 -3.81 0)
      (effects (font (size 1.27 1.27)) hide)
    )
  )
  (global_label "A6" (shape input) (at 245.745 120.65 180) (fields_autoplaced)
    (effects (font (size 1.27 1.27)) (justify right))
    (property "Intersheetrefs" "${INTERSHEET_REFS}" (at 12.065 -14.605 0)
      (effects (font (size 1.27 1.27)) hide)
    )
  )
  (global_label "DQS1_P" (shape input) (at 317.5 123.19 180) (fields_autoplaced)
    (effects (font (size 1.27 1.27)) (justify right))
    (property "Intersheetrefs" "${INTERSHEET_REFS}" (at 307.9187 123.1106 0)
      (effects (font (size 1.27 1.27)) (justify right) hide)
    )
  )
  (global_label "DQ4" (shape input) (at 317.5 87.63 180) (fields_autoplaced)
    (effects (font (size 1.27 1.27)) (justify right))
    (property "Intersheetrefs" "${INTERSHEET_REFS}" (at 311.3658 87.5506 0)
      (effects (font (size 1.27 1.27)) (justify right) hide)
    )
  )
  (global_label "~{EVENT}" (shape input) (at 245.745 85.09 180) (fields_autoplaced)
    (effects (font (size 1.27 1.27)) (justify right))
    (property "Intersheetrefs" "${INTERSHEET_REFS}" (at 411.48 168.91 0)
      (effects (font (size 1.27 1.27)) hide)
    )
  )
  (global_label "VRN" (shape input) (at 245.745 64.77 180) (fields_autoplaced)
    (effects (font (size 1.27 1.27)) (justify right))
    (property "Intersheetrefs" "${INTERSHEET_REFS}" (at 12.065 -14.605 0)
      (effects (font (size 1.27 1.27)) hide)
    )
  )
  (global_label "DQ41" (shape input) (at 127 151.13 180) (fields_autoplaced)
    (effects (font (size 1.27 1.27)) (justify right))
    (property "Intersheetrefs" "${INTERSHEET_REFS}" (at 119.6563 151.0506 0)
      (effects (font (size 1.27 1.27)) (justify right) hide)
    )
  )
  (global_label "DQ44" (shape input) (at 127 102.87 180) (fields_autoplaced)
    (effects (font (size 1.27 1.27)) (justify right))
    (property "Intersheetrefs" "${INTERSHEET_REFS}" (at 119.6563 102.7906 0)
      (effects (font (size 1.27 1.27)) (justify right) hide)
    )
  )
  (global_label "DQS15_N" (shape input) (at 127 120.65 180) (fields_autoplaced)
    (effects (font (size 1.27 1.27)) (justify right))
    (property "Intersheetrefs" "${INTERSHEET_REFS}" (at 116.1487 120.5706 0)
      (effects (font (size 1.27 1.27)) (justify right) hide)
    )
  )
  (global_label "A4" (shape input) (at 245.745 123.19 180) (fields_autoplaced)
    (effects (font (size 1.27 1.27)) (justify right))
    (property "Intersheetrefs" "${INTERSHEET_REFS}" (at 12.065 -14.605 0)
      (effects (font (size 1.27 1.27)) hide)
    )
  )
  (global_label "DQ53" (shape input) (at 127 123.19 180) (fields_autoplaced)
    (effects (font (size 1.27 1.27)) (justify right))
    (property "Intersheetrefs" "${INTERSHEET_REFS}" (at 119.6563 123.1106 0)
      (effects (font (size 1.27 1.27)) (justify right) hide)
    )
  )
  (global_label "ODT1\\NC" (shape input) (at 245.745 80.01 180) (fields_autoplaced)
    (effects (font (size 1.27 1.27)) (justify right))
    (property "Intersheetrefs" "${INTERSHEET_REFS}" (at 411.48 204.47 0)
      (effects (font (size 1.27 1.27)) hide)
    )
  )
  (global_label "VRP" (shape input) (at 376.555 241.3 180) (fields_autoplaced)
    (effects (font (size 1.27 1.27)) (justify right))
    (property "Intersheetrefs" "${INTERSHEET_REFS}" (at 160.02 -34.29 0)
      (effects (font (size 1.27 1.27)) hide)
    )
  )

  (symbol (lib_id "antmicroResistors0402:R_10k_0402") (at 255.905 85.09 180) (unit 1)
    (in_bom yes) (on_board yes) (dnp no)
    (property "Reference" "R163" (at 248.285 83.82 0)
      (effects (font (size 1.524 1.524)))
    )
    (property "Value" "R_10k_0402" (at 235.585 72.39 0)
      (effects (font (size 1.27 1.27) (thickness 0.15)) (justify left bottom) hide)
    )
    (property "Footprint" "antmicro-footprints:R_0402_1005Metric" (at 235.585 69.85 0)
      (effects (font (size 1.27 1.27) (thickness 0.15)) (justify left bottom) hide)
    )
    (property "Datasheet" "https://www.bourns.com/docs/product-datasheets/cr.pdf" (at 235.585 67.31 0)
      (effects (font (size 1.27 1.27) (thickness 0.15)) (justify left bottom) hide)
    )
    (property "Manufacturer" "Bourns" (at 235.585 62.23 0)
      (effects (font (size 1.27 1.27) (thickness 0.15)) (justify left bottom) hide)
    )
    (property "MPN" "CR0402-FX-1002GLF" (at 235.585 64.77 0)
      (effects (font (size 1.27 1.27) (thickness 0.15)) (justify left bottom) hide)
    )
    (property "Val" "10k" (at 257.175 83.82 0)
      (effects (font (size 1.27 1.27) (thickness 0.15)))
    )
    (property "License" "Apache-2.0" (at 235.585 59.69 0)
      (effects (font (size 1.27 1.27) (thickness 0.15)) (justify left bottom) hide)
    )
    (property "Author" "Antmicro" (at 235.585 57.15 0)
      (effects (font (size 1.27 1.27) (thickness 0.15)) (justify left bottom) hide)
    )
    (property "Tolerance" "1%" (at 235.585 74.93 0)
      (effects (font (size 1.27 1.27)) (justify left bottom) hide)
    )
    (pin "1")
    (pin "2")
    (instances
      (project "data-center-rdimm-ddr4-tester"
        (path ""
          (reference "R163") (unit 1)
        )
      )
    )
  )

  (symbol (lib_id "antmicroLogicTranslatorsLevelShifters:PCA9517A_TSSOP") (at 214.63 240.03 0) (mirror y) (unit 1)
    (in_bom yes) (on_board yes) (dnp no)
    (property "Reference" "U8" (at 205.105 233.045 0)
      (effects (font (size 1.524 1.524)))
    )
    (property "Value" "PCA9517A_TSSOP" (at 205.105 262.255 0)
      (effects (font (size 1.27 1.27) (thickness 0.15)) hide)
    )
    (property "Footprint" "antmicro-footprints:TSSOP-8_3x3mm_P0.65mm" (at 181.61 247.65 0)
      (effects (font (size 1.27 1.27) (thickness 0.15)) (justify left bottom) hide)
    )
    (property "Datasheet" "https://www.mouser.pl/datasheet/2/308/1/ONSM_S_A0009688870_1-2560458.pdf" (at 181.61 250.19 0)
      (effects (font (size 1.27 1.27) (thickness 0.15)) (justify left bottom) hide)
    )
    (property "MPN" "PCA9517ADMR2G" (at 205.105 235.585 0)
      (effects (font (size 1.27 1.27) (thickness 0.15)))
    )
    (property "Manufacturer" "ON Semiconductor" (at 181.61 255.27 0)
      (effects (font (size 1.27 1.27) (thickness 0.15)) (justify left bottom) hide)
    )
    (property "Author" "Antmicro" (at 181.61 257.81 0)
      (effects (font (size 1.27 1.27) (thickness 0.15)) (justify left bottom) hide)
    )
    (property "License" "Apache-2.0" (at 181.61 260.35 0)
      (effects (font (size 1.27 1.27) (thickness 0.15)) (justify left bottom) hide)
    )
    (pin "1")
    (pin "2")
    (pin "3")
    (pin "4")
    (pin "5")
    (pin "6")
    (pin "7")
    (pin "8")
    (instances
      (project "data-center-rdimm-ddr4-tester"
        (path ""
          (reference "U8") (unit 1)
        )
      )
    )
  )

  (symbol (lib_id "antmicroResistors0402:R_4k7_0402") (at 227.33 240.665 270) (unit 1)
    (in_bom yes) (on_board yes) (dnp no)
    (property "Reference" "R173" (at 226.06 241.935 90)
      (effects (font (size 1.524 1.524)) (justify right))
    )
    (property "Value" "R_4k7_0402" (at 214.63 260.985 0)
      (effects (font (size 1.27 1.27) (thickness 0.15)) (justify left bottom) hide)
    )
    (property "Footprint" "antmicro-footprints:R_0402_1005Metric" (at 212.09 260.985 0)
      (effects (font (size 1.27 1.27) (thickness 0.15)) (justify left bottom) hide)
    )
    (property "Datasheet" "https://www.bourns.com/docs/product-datasheets/cr.pdf" (at 209.55 260.985 0)
      (effects (font (size 1.27 1.27) (thickness 0.15)) (justify left bottom) hide)
    )
    (property "Manufacturer" "Bourns" (at 204.47 260.985 0)
      (effects (font (size 1.27 1.27) (thickness 0.15)) (justify left bottom) hide)
    )
    (property "MPN" "CR0402-FX-4701GLF" (at 207.01 260.985 0)
      (effects (font (size 1.27 1.27) (thickness 0.15)) (justify left bottom) hide)
    )
    (property "Val" "4k7" (at 226.06 244.475 90)
      (effects (font (size 1.27 1.27) (thickness 0.15)) (justify right))
    )
    (property "License" "Apache-2.0" (at 201.93 260.985 0)
      (effects (font (size 1.27 1.27) (thickness 0.15)) (justify left bottom) hide)
    )
    (property "Author" "Antmicro" (at 199.39 260.985 0)
      (effects (font (size 1.27 1.27) (thickness 0.15)) (justify left bottom) hide)
    )
    (property "Tolerance" "1%" (at 217.17 260.985 0)
      (effects (font (size 1.27 1.27)) (justify left bottom) hide)
    )
    (pin "1")
    (pin "2")
    (instances
      (project "data-center-rdimm-ddr4-tester"
        (path ""
          (reference "R173") (unit 1)
        )
      )
    )
  )

  (symbol (lib_id "antmicroResistors0402:R_4k7_0402") (at 230.505 240.665 270) (unit 1)
    (in_bom yes) (on_board yes) (dnp no)
    (property "Reference" "R174" (at 231.775 241.935 90)
      (effects (font (size 1.524 1.524)) (justify left))
    )
    (property "Value" "R_4k7_0402" (at 217.805 260.985 0)
      (effects (font (size 1.27 1.27) (thickness 0.15)) (justify left bottom) hide)
    )
    (property "Footprint" "antmicro-footprints:R_0402_1005Metric" (at 215.265 260.985 0)
      (effects (font (size 1.27 1.27) (thickness 0.15)) (justify left bottom) hide)
    )
    (property "Datasheet" "https://www.bourns.com/docs/product-datasheets/cr.pdf" (at 212.725 260.985 0)
      (effects (font (size 1.27 1.27) (thickness 0.15)) (justify left bottom) hide)
    )
    (property "Manufacturer" "Bourns" (at 207.645 260.985 0)
      (effects (font (size 1.27 1.27) (thickness 0.15)) (justify left bottom) hide)
    )
    (property "MPN" "CR0402-FX-4701GLF" (at 210.185 260.985 0)
      (effects (font (size 1.27 1.27) (thickness 0.15)) (justify left bottom) hide)
    )
    (property "Val" "4k7" (at 231.775 244.475 90)
      (effects (font (size 1.27 1.27) (thickness 0.15)) (justify left))
    )
    (property "License" "Apache-2.0" (at 205.105 260.985 0)
      (effects (font (size 1.27 1.27) (thickness 0.15)) (justify left bottom) hide)
    )
    (property "Author" "Antmicro" (at 202.565 260.985 0)
      (effects (font (size 1.27 1.27) (thickness 0.15)) (justify left bottom) hide)
    )
    (property "Tolerance" "1%" (at 220.345 260.985 0)
      (effects (font (size 1.27 1.27)) (justify left bottom) hide)
    )
    (pin "1")
    (pin "2")
    (instances
      (project "data-center-rdimm-ddr4-tester"
        (path ""
          (reference "R174") (unit 1)
        )
      )
    )
  )

  (symbol (lib_id "antmicroMicrocontrollers:XC7K160T-FFG676") (at 55.88 59.69 0) (unit 5)
    (in_bom yes) (on_board yes) (dnp no) (fields_autoplaced)
    (property "Reference" "U15" (at 78.74 52.07 0)
      (effects (font (size 1.27 1.27)))
    )
    (property "Value" "XC7K160T-FFG676" (at 78.74 54.61 0)
      (effects (font (size 1.27 1.27) (thickness 0.15)))
    )
    (property "Footprint" "antmicro-footprints:BGA-676_27x27mm_Layout26x26_P1X1mm" (at 124.46 62.23 0)
      (effects (font (size 1.27 1.27) (thickness 0.15)) (justify left bottom) hide)
    )
    (property "Datasheet" "https://docs.xilinx.com/v/u/en-US/ds180_7Series_Overview" (at 124.46 64.77 0)
      (effects (font (size 1.27 1.27) (thickness 0.15)) (justify left bottom) hide)
    )
    (property "MPN" "XC7K160T-FFG676" (at 55.88 59.69 0)
      (effects (font (size 1.27 1.27)) hide)
    )
    (property "Author" "Antmicro" (at 124.46 67.31 0)
      (effects (font (size 1.27 1.27) (thickness 0.15)) (justify left bottom) hide)
    )
    (property "License" "Apache-2.0" (at 124.46 69.85 0)
      (effects (font (size 1.27 1.27) (thickness 0.15)) (justify left bottom) hide)
    )
    (property "Manufacturer" "AMD-Xilinx" (at 55.88 59.69 0)
      (effects (font (size 1.27 1.27)) hide)
    )
    (pin "AA21")
    (pin "AA22")
    (pin "AA23")
    (pin "AA24")
    (pin "AA25")
    (pin "AB21")
    (pin "AB22")
    (pin "AB24")
    (pin "AB25")
    (pin "AB26")
    (pin "AC21")
    (pin "AC22")
    (pin "AC23")
    (pin "AC24")
    (pin "AC25")
    (pin "AC26")
    (pin "AD21")
    (pin "AD22")
    (pin "AD23")
    (pin "AD24")
    (pin "AD25")
    (pin "AD26")
    (pin "AE21")
    (pin "AE22")
    (pin "AE23")
    (pin "AE25")
    (pin "AE26")
    (pin "AF22")
    (pin "AF23")
    (pin "AF24")
    (pin "AF25")
    (pin "AF26")
    (pin "U21")
    (pin "U22")
    (pin "U23")
    (pin "U24")
    (pin "U25")
    (pin "U26")
    (pin "V20")
    (pin "V21")
    (pin "V22")
    (pin "V23")
    (pin "V24")
    (pin "V26")
    (pin "W20")
    (pin "W21")
    (pin "W23")
    (pin "W24")
    (pin "W25")
    (pin "W26")
    (pin "Y20")
    (pin "Y21")
    (pin "Y22")
    (pin "Y23")
    (pin "Y24")
    (pin "Y25")
    (pin "Y26")
    (pin "K24")
    (pin "K25")
    (pin "K26")
    (pin "L24")
    (pin "L25")
    (pin "M19")
    (pin "M20")
    (pin "M21")
    (pin "M22")
    (pin "M24")
    (pin "M25")
    (pin "M26")
    (pin "N16")
    (pin "N17")
    (pin "N18")
    (pin "N19")
    (pin "N21")
    (pin "N22")
    (pin "N23")
    (pin "N24")
    (pin "N25")
    (pin "N26")
    (pin "P16")
    (pin "P18")
    (pin "P19")
    (pin "P20")
    (pin "P21")
    (pin "P22")
    (pin "P23")
    (pin "P24")
    (pin "P25")
    (pin "P26")
    (pin "R16")
    (pin "R17")
    (pin "R18")
    (pin "R19")
    (pin "R20")
    (pin "R21")
    (pin "R22")
    (pin "R23")
    (pin "R25")
    (pin "R26")
    (pin "T16")
    (pin "T17")
    (pin "T18")
    (pin "T19")
    (pin "T20")
    (pin "T22")
    (pin "T23")
    (pin "T24")
    (pin "T25")
    (pin "T26")
    (pin "U16")
    (pin "U17")
    (pin "U19")
    (pin "U20")
    (pin "A20")
    (pin "A21")
    (pin "A22")
    (pin "A23")
    (pin "A24")
    (pin "A25")
    (pin "B20")
    (pin "B21")
    (pin "B22")
    (pin "B24")
    (pin "B25")
    (pin "B26")
    (pin "C21")
    (pin "C22")
    (pin "C23")
    (pin "C24")
    (pin "C25")
    (pin "C26")
    (pin "D21")
    (pin "D22")
    (pin "D23")
    (pin "D24")
    (pin "D25")
    (pin "D26")
    (pin "E21")
    (pin "E22")
    (pin "E23")
    (pin "E25")
    (pin "E26")
    (pin "F22")
    (pin "F23")
    (pin "F24")
    (pin "F25")
    (pin "F26")
    (pin "G21")
    (pin "G22")
    (pin "G23")
    (pin "G24")
    (pin "G25")
    (pin "G26")
    (pin "H21")
    (pin "H22")
    (pin "H23")
    (pin "H24")
    (pin "H26")
    (pin "J21")
    (pin "J23")
    (pin "J24")
    (pin "J25")
    (pin "J26")
    (pin "K21")
    (pin "K22")
    (pin "K23")
    (pin "L21")
    (pin "L22")
    (pin "L23")
    (pin "A17")
    (pin "A18")
    (pin "A19")
    (pin "B16")
    (pin "B17")
    (pin "B18")
    (pin "B19")
    (pin "C16")
    (pin "C17")
    (pin "C18")
    (pin "C19")
    (pin "D15")
    (pin "D16")
    (pin "D18")
    (pin "D19")
    (pin "D20")
    (pin "E15")
    (pin "E16")
    (pin "E17")
    (pin "E18")
    (pin "E19")
    (pin "E20")
    (pin "F15")
    (pin "F16")
    (pin "F17")
    (pin "F18")
    (pin "F19")
    (pin "F20")
    (pin "G15")
    (pin "G16")
    (pin "G17")
    (pin "G19")
    (pin "G20")
    (pin "H16")
    (pin "H17")
    (pin "H18")
    (pin "H19")
    (pin "H20")
    (pin "J15")
    (pin "J16")
    (pin "J17")
    (pin "J18")
    (pin "J19")
    (pin "J20")
    (pin "K15")
    (pin "K16")
    (pin "K17")
    (pin "K18")
    (pin "K20")
    (pin "L17")
    (pin "L18")
    (pin "L19")
    (pin "L20")
    (pin "M16")
    (pin "M17")
    (pin "M18")
    (pin "A10")
    (pin "A11")
    (pin "A12")
    (pin "A13")
    (pin "A14")
    (pin "A15")
    (pin "A8")
    (pin "A9")
    (pin "B10")
    (pin "B11")
    (pin "B12")
    (pin "B14")
    (pin "B15")
    (pin "B8")
    (pin "B9")
    (pin "C11")
    (pin "C12")
    (pin "C13")
    (pin "C14")
    (pin "C15")
    (pin "C9")
    (pin "D10")
    (pin "D11")
    (pin "D12")
    (pin "D13")
    (pin "D14")
    (pin "D8")
    (pin "D9")
    (pin "E10")
    (pin "E11")
    (pin "E12")
    (pin "E13")
    (pin "E9")
    (pin "F10")
    (pin "F12")
    (pin "F13")
    (pin "F14")
    (pin "F8")
    (pin "F9")
    (pin "G10")
    (pin "G11")
    (pin "G12")
    (pin "G13")
    (pin "G14")
    (pin "G9")
    (pin "H10")
    (pin "H11")
    (pin "H12")
    (pin "H13")
    (pin "H14")
    (pin "H8")
    (pin "H9")
    (pin "J10")
    (pin "J11")
    (pin "J13")
    (pin "J14")
    (pin "J8")
    (pin "AA14")
    (pin "AA15")
    (pin "AA17")
    (pin "AA18")
    (pin "AA19")
    (pin "AA20")
    (pin "AB14")
    (pin "AB15")
    (pin "AB16")
    (pin "AB17")
    (pin "AB18")
    (pin "AB19")
    (pin "AB20")
    (pin "AC14")
    (pin "AC15")
    (pin "AC16")
    (pin "AC17")
    (pin "AC18")
    (pin "AC19")
    (pin "AD14")
    (pin "AD15")
    (pin "AD16")
    (pin "AD18")
    (pin "AD19")
    (pin "AD20")
    (pin "AE15")
    (pin "AE16")
    (pin "AE17")
    (pin "AE18")
    (pin "AE19")
    (pin "AE20")
    (pin "AF14")
    (pin "AF15")
    (pin "AF16")
    (pin "AF17")
    (pin "AF18")
    (pin "AF19")
    (pin "AF20")
    (pin "V13")
    (pin "V14")
    (pin "V16")
    (pin "V17")
    (pin "V18")
    (pin "V19")
    (pin "W13")
    (pin "W14")
    (pin "W15")
    (pin "W16")
    (pin "W17")
    (pin "W18")
    (pin "W19")
    (pin "Y14")
    (pin "Y15")
    (pin "Y16")
    (pin "Y17")
    (pin "Y18")
    (pin "AA10")
    (pin "AA11")
    (pin "AA12")
    (pin "AA13")
    (pin "AA7")
    (pin "AA8")
    (pin "AA9")
    (pin "AB10")
    (pin "AB11")
    (pin "AB12")
    (pin "AB7")
    (pin "AB8")
    (pin "AB9")
    (pin "AC11")
    (pin "AC12")
    (pin "AC13")
    (pin "AC7")
    (pin "AC8")
    (pin "AC9")
    (pin "AD10")
    (pin "AD11")
    (pin "AD12")
    (pin "AD13")
    (pin "AD8")
    (pin "AD9")
    (pin "AE10")
    (pin "AE11")
    (pin "AE12")
    (pin "AE13")
    (pin "AE7")
    (pin "AE8")
    (pin "AE9")
    (pin "AF10")
    (pin "AF12")
    (pin "AF13")
    (pin "AF7")
    (pin "AF8")
    (pin "AF9")
    (pin "U9")
    (pin "V10")
    (pin "V11")
    (pin "V12")
    (pin "V7")
    (pin "V8")
    (pin "V9")
    (pin "W10")
    (pin "W11")
    (pin "W7")
    (pin "W8")
    (pin "W9")
    (pin "Y10")
    (pin "Y11")
    (pin "Y12")
    (pin "Y13")
    (pin "Y7")
    (pin "Y8")
    (pin "AA1")
    (pin "AA2")
    (pin "AA3")
    (pin "AA4")
    (pin "AA5")
    (pin "AB1")
    (pin "AB2")
    (pin "AB4")
    (pin "AB5")
    (pin "AB6")
    (pin "AC1")
    (pin "AC2")
    (pin "AC3")
    (pin "AC4")
    (pin "AC5")
    (pin "AC6")
    (pin "AD1")
    (pin "AD2")
    (pin "AD3")
    (pin "AD4")
    (pin "AD5")
    (pin "AD6")
    (pin "AE1")
    (pin "AE2")
    (pin "AE3")
    (pin "AE5")
    (pin "AE6")
    (pin "AF2")
    (pin "AF3")
    (pin "AF4")
    (pin "AF5")
    (pin "AF6")
    (pin "T7")
    (pin "U1")
    (pin "U2")
    (pin "U3")
    (pin "U4")
    (pin "U5")
    (pin "U6")
    (pin "U7")
    (pin "V1")
    (pin "V2")
    (pin "V3")
    (pin "V4")
    (pin "V6")
    (pin "W1")
    (pin "W3")
    (pin "W4")
    (pin "W5")
    (pin "W6")
    (pin "Y1")
    (pin "Y2")
    (pin "Y3")
    (pin "Y4")
    (pin "Y5")
    (pin "Y6")
    (pin "A3")
    (pin "A4")
    (pin "B1")
    (pin "B2")
    (pin "B5")
    (pin "B6")
    (pin "C3")
    (pin "C4")
    (pin "D1")
    (pin "D2")
    (pin "D5")
    (pin "D6")
    (pin "E3")
    (pin "E4")
    (pin "F1")
    (pin "F2")
    (pin "F5")
    (pin "F6")
    (pin "G3")
    (pin "G4")
    (pin "H1")
    (pin "H2")
    (pin "H5")
    (pin "H6")
    (pin "J3")
    (pin "J4")
    (pin "K1")
    (pin "K2")
    (pin "K5")
    (pin "K6")
    (pin "L3")
    (pin "L4")
    (pin "M1")
    (pin "M2")
    (pin "N3")
    (pin "N4")
    (pin "P1")
    (pin "P2")
    (pin "R3")
    (pin "R4")
    (pin "A1")
    (pin "A16")
    (pin "A2")
    (pin "A26")
    (pin "A5")
    (pin "A6")
    (pin "A7")
    (pin "AA16")
    (pin "AA26")
    (pin "AA6")
    (pin "AB13")
    (pin "AB23")
    (pin "AB3")
    (pin "AC10")
    (pin "AC20")
    (pin "AD17")
    (pin "AD7")
    (pin "AE14")
    (pin "AE24")
    (pin "AE4")
    (pin "AF1")
    (pin "AF11")
    (pin "AF21")
    (pin "B13")
    (pin "B23")
    (pin "B3")
    (pin "B4")
    (pin "B7")
    (pin "C1")
    (pin "C10")
    (pin "C2")
    (pin "C20")
    (pin "C5")
    (pin "C6")
    (pin "C7")
    (pin "D17")
    (pin "D3")
    (pin "D4")
    (pin "D7")
    (pin "E1")
    (pin "E14")
    (pin "E2")
    (pin "E24")
    (pin "E5")
    (pin "E6")
    (pin "E7")
    (pin "E8")
    (pin "F11")
    (pin "F21")
    (pin "F3")
    (pin "F4")
    (pin "F7")
    (pin "G1")
    (pin "G18")
    (pin "G2")
    (pin "G5")
    (pin "G6")
    (pin "G8")
    (pin "H15")
    (pin "H25")
    (pin "H3")
    (pin "H4")
    (pin "H7")
    (pin "J1")
    (pin "J12")
    (pin "J2")
    (pin "J22")
    (pin "J5")
    (pin "J6")
    (pin "J9")
    (pin "K10")
    (pin "K11")
    (pin "K12")
    (pin "K13")
    (pin "K14")
    (pin "K19")
    (pin "K3")
    (pin "K4")
    (pin "K7")
    (pin "K8")
    (pin "K9")
    (pin "L1")
    (pin "L10")
    (pin "L11")
    (pin "L12")
    (pin "L13")
    (pin "L14")
    (pin "L15")
    (pin "L16")
    (pin "L2")
    (pin "L26")
    (pin "L5")
    (pin "L6")
    (pin "L9")
    (pin "M10")
    (pin "M11")
    (pin "M12")
    (pin "M13")
    (pin "M14")
    (pin "M15")
    (pin "M23")
    (pin "M3")
    (pin "M4")
    (pin "M5")
    (pin "M6")
    (pin "M7")
    (pin "M8")
    (pin "M9")
    (pin "N1")
    (pin "N10")
    (pin "N13")
    (pin "N14")
    (pin "N15")
    (pin "N2")
    (pin "N20")
    (pin "N5")
    (pin "N6")
    (pin "N7")
    (pin "N9")
    (pin "P10")
    (pin "P13")
    (pin "P14")
    (pin "P15")
    (pin "P17")
    (pin "P3")
    (pin "P4")
    (pin "P8")
    (pin "P9")
    (pin "R1")
    (pin "R10")
    (pin "R13")
    (pin "R14")
    (pin "R15")
    (pin "R2")
    (pin "R24")
    (pin "R5")
    (pin "R8")
    (pin "R9")
    (pin "T1")
    (pin "T10")
    (pin "T11")
    (pin "T12")
    (pin "T13")
    (pin "T14")
    (pin "T15")
    (pin "T21")
    (pin "T3")
    (pin "T4")
    (pin "T8")
    (pin "T9")
    (pin "U10")
    (pin "U11")
    (pin "U12")
    (pin "U13")
    (pin "U14")
    (pin "U15")
    (pin "U18")
    (pin "U8")
    (pin "V15")
    (pin "V25")
    (pin "V5")
    (pin "W12")
    (pin "W2")
    (pin "W22")
    (pin "Y19")
    (pin "Y9")
    (pin "C8")
    (pin "G7")
    (pin "J7")
    (pin "L7")
    (pin "L8")
    (pin "N11")
    (pin "N12")
    (pin "N8")
    (pin "P11")
    (pin "P12")
    (pin "P5")
    (pin "P6")
    (pin "P7")
    (pin "R11")
    (pin "R12")
    (pin "R6")
    (pin "R7")
    (pin "T2")
    (pin "T5")
    (pin "T6")
    (instances
      (project "data-center-rdimm-ddr4-tester"
        (path ""
          (reference "U15") (unit 5)
        )
      )
    )
  )

  (symbol (lib_id "antmicroMicrocontrollers:XC7K160T-FFG676") (at 138.43 59.69 0) (unit 6)
    (in_bom yes) (on_board yes) (dnp no) (fields_autoplaced)
    (property "Reference" "U15" (at 161.29 51.435 0)
      (effects (font (size 1.27 1.27)))
    )
    (property "Value" "XC7K160T-FFG676" (at 161.29 53.975 0)
      (effects (font (size 1.27 1.27) (thickness 0.15)))
    )
    (property "Footprint" "antmicro-footprints:BGA-676_27x27mm_Layout26x26_P1X1mm" (at 207.01 62.23 0)
      (effects (font (size 1.27 1.27) (thickness 0.15)) (justify left bottom) hide)
    )
    (property "Datasheet" "https://docs.xilinx.com/v/u/en-US/ds180_7Series_Overview" (at 207.01 64.77 0)
      (effects (font (size 1.27 1.27) (thickness 0.15)) (justify left bottom) hide)
    )
    (property "MPN" "XC7K160T-FFG676" (at 138.43 59.69 0)
      (effects (font (size 1.27 1.27)) hide)
    )
    (property "Author" "Antmicro" (at 207.01 67.31 0)
      (effects (font (size 1.27 1.27) (thickness 0.15)) (justify left bottom) hide)
    )
    (property "License" "Apache-2.0" (at 207.01 69.85 0)
      (effects (font (size 1.27 1.27) (thickness 0.15)) (justify left bottom) hide)
    )
    (property "Manufacturer" "AMD-Xilinx" (at 138.43 59.69 0)
      (effects (font (size 1.27 1.27)) hide)
    )
    (pin "AA21")
    (pin "AA22")
    (pin "AA23")
    (pin "AA24")
    (pin "AA25")
    (pin "AB21")
    (pin "AB22")
    (pin "AB24")
    (pin "AB25")
    (pin "AB26")
    (pin "AC21")
    (pin "AC22")
    (pin "AC23")
    (pin "AC24")
    (pin "AC25")
    (pin "AC26")
    (pin "AD21")
    (pin "AD22")
    (pin "AD23")
    (pin "AD24")
    (pin "AD25")
    (pin "AD26")
    (pin "AE21")
    (pin "AE22")
    (pin "AE23")
    (pin "AE25")
    (pin "AE26")
    (pin "AF22")
    (pin "AF23")
    (pin "AF24")
    (pin "AF25")
    (pin "AF26")
    (pin "U21")
    (pin "U22")
    (pin "U23")
    (pin "U24")
    (pin "U25")
    (pin "U26")
    (pin "V20")
    (pin "V21")
    (pin "V22")
    (pin "V23")
    (pin "V24")
    (pin "V26")
    (pin "W20")
    (pin "W21")
    (pin "W23")
    (pin "W24")
    (pin "W25")
    (pin "W26")
    (pin "Y20")
    (pin "Y21")
    (pin "Y22")
    (pin "Y23")
    (pin "Y24")
    (pin "Y25")
    (pin "Y26")
    (pin "K24")
    (pin "K25")
    (pin "K26")
    (pin "L24")
    (pin "L25")
    (pin "M19")
    (pin "M20")
    (pin "M21")
    (pin "M22")
    (pin "M24")
    (pin "M25")
    (pin "M26")
    (pin "N16")
    (pin "N17")
    (pin "N18")
    (pin "N19")
    (pin "N21")
    (pin "N22")
    (pin "N23")
    (pin "N24")
    (pin "N25")
    (pin "N26")
    (pin "P16")
    (pin "P18")
    (pin "P19")
    (pin "P20")
    (pin "P21")
    (pin "P22")
    (pin "P23")
    (pin "P24")
    (pin "P25")
    (pin "P26")
    (pin "R16")
    (pin "R17")
    (pin "R18")
    (pin "R19")
    (pin "R20")
    (pin "R21")
    (pin "R22")
    (pin "R23")
    (pin "R25")
    (pin "R26")
    (pin "T16")
    (pin "T17")
    (pin "T18")
    (pin "T19")
    (pin "T20")
    (pin "T22")
    (pin "T23")
    (pin "T24")
    (pin "T25")
    (pin "T26")
    (pin "U16")
    (pin "U17")
    (pin "U19")
    (pin "U20")
    (pin "A20")
    (pin "A21")
    (pin "A22")
    (pin "A23")
    (pin "A24")
    (pin "A25")
    (pin "B20")
    (pin "B21")
    (pin "B22")
    (pin "B24")
    (pin "B25")
    (pin "B26")
    (pin "C21")
    (pin "C22")
    (pin "C23")
    (pin "C24")
    (pin "C25")
    (pin "C26")
    (pin "D21")
    (pin "D22")
    (pin "D23")
    (pin "D24")
    (pin "D25")
    (pin "D26")
    (pin "E21")
    (pin "E22")
    (pin "E23")
    (pin "E25")
    (pin "E26")
    (pin "F22")
    (pin "F23")
    (pin "F24")
    (pin "F25")
    (pin "F26")
    (pin "G21")
    (pin "G22")
    (pin "G23")
    (pin "G24")
    (pin "G25")
    (pin "G26")
    (pin "H21")
    (pin "H22")
    (pin "H23")
    (pin "H24")
    (pin "H26")
    (pin "J21")
    (pin "J23")
    (pin "J24")
    (pin "J25")
    (pin "J26")
    (pin "K21")
    (pin "K22")
    (pin "K23")
    (pin "L21")
    (pin "L22")
    (pin "L23")
    (pin "A17")
    (pin "A18")
    (pin "A19")
    (pin "B16")
    (pin "B17")
    (pin "B18")
    (pin "B19")
    (pin "C16")
    (pin "C17")
    (pin "C18")
    (pin "C19")
    (pin "D15")
    (pin "D16")
    (pin "D18")
    (pin "D19")
    (pin "D20")
    (pin "E15")
    (pin "E16")
    (pin "E17")
    (pin "E18")
    (pin "E19")
    (pin "E20")
    (pin "F15")
    (pin "F16")
    (pin "F17")
    (pin "F18")
    (pin "F19")
    (pin "F20")
    (pin "G15")
    (pin "G16")
    (pin "G17")
    (pin "G19")
    (pin "G20")
    (pin "H16")
    (pin "H17")
    (pin "H18")
    (pin "H19")
    (pin "H20")
    (pin "J15")
    (pin "J16")
    (pin "J17")
    (pin "J18")
    (pin "J19")
    (pin "J20")
    (pin "K15")
    (pin "K16")
    (pin "K17")
    (pin "K18")
    (pin "K20")
    (pin "L17")
    (pin "L18")
    (pin "L19")
    (pin "L20")
    (pin "M16")
    (pin "M17")
    (pin "M18")
    (pin "A10")
    (pin "A11")
    (pin "A12")
    (pin "A13")
    (pin "A14")
    (pin "A15")
    (pin "A8")
    (pin "A9")
    (pin "B10")
    (pin "B11")
    (pin "B12")
    (pin "B14")
    (pin "B15")
    (pin "B8")
    (pin "B9")
    (pin "C11")
    (pin "C12")
    (pin "C13")
    (pin "C14")
    (pin "C15")
    (pin "C9")
    (pin "D10")
    (pin "D11")
    (pin "D12")
    (pin "D13")
    (pin "D14")
    (pin "D8")
    (pin "D9")
    (pin "E10")
    (pin "E11")
    (pin "E12")
    (pin "E13")
    (pin "E9")
    (pin "F10")
    (pin "F12")
    (pin "F13")
    (pin "F14")
    (pin "F8")
    (pin "F9")
    (pin "G10")
    (pin "G11")
    (pin "G12")
    (pin "G13")
    (pin "G14")
    (pin "G9")
    (pin "H10")
    (pin "H11")
    (pin "H12")
    (pin "H13")
    (pin "H14")
    (pin "H8")
    (pin "H9")
    (pin "J10")
    (pin "J11")
    (pin "J13")
    (pin "J14")
    (pin "J8")
    (pin "AA14")
    (pin "AA15")
    (pin "AA17")
    (pin "AA18")
    (pin "AA19")
    (pin "AA20")
    (pin "AB14")
    (pin "AB15")
    (pin "AB16")
    (pin "AB17")
    (pin "AB18")
    (pin "AB19")
    (pin "AB20")
    (pin "AC14")
    (pin "AC15")
    (pin "AC16")
    (pin "AC17")
    (pin "AC18")
    (pin "AC19")
    (pin "AD14")
    (pin "AD15")
    (pin "AD16")
    (pin "AD18")
    (pin "AD19")
    (pin "AD20")
    (pin "AE15")
    (pin "AE16")
    (pin "AE17")
    (pin "AE18")
    (pin "AE19")
    (pin "AE20")
    (pin "AF14")
    (pin "AF15")
    (pin "AF16")
    (pin "AF17")
    (pin "AF18")
    (pin "AF19")
    (pin "AF20")
    (pin "V13")
    (pin "V14")
    (pin "V16")
    (pin "V17")
    (pin "V18")
    (pin "V19")
    (pin "W13")
    (pin "W14")
    (pin "W15")
    (pin "W16")
    (pin "W17")
    (pin "W18")
    (pin "W19")
    (pin "Y14")
    (pin "Y15")
    (pin "Y16")
    (pin "Y17")
    (pin "Y18")
    (pin "AA10")
    (pin "AA11")
    (pin "AA12")
    (pin "AA13")
    (pin "AA7")
    (pin "AA8")
    (pin "AA9")
    (pin "AB10")
    (pin "AB11")
    (pin "AB12")
    (pin "AB7")
    (pin "AB8")
    (pin "AB9")
    (pin "AC11")
    (pin "AC12")
    (pin "AC13")
    (pin "AC7")
    (pin "AC8")
    (pin "AC9")
    (pin "AD10")
    (pin "AD11")
    (pin "AD12")
    (pin "AD13")
    (pin "AD8")
    (pin "AD9")
    (pin "AE10")
    (pin "AE11")
    (pin "AE12")
    (pin "AE13")
    (pin "AE7")
    (pin "AE8")
    (pin "AE9")
    (pin "AF10")
    (pin "AF12")
    (pin "AF13")
    (pin "AF7")
    (pin "AF8")
    (pin "AF9")
    (pin "U9")
    (pin "V10")
    (pin "V11")
    (pin "V12")
    (pin "V7")
    (pin "V8")
    (pin "V9")
    (pin "W10")
    (pin "W11")
    (pin "W7")
    (pin "W8")
    (pin "W9")
    (pin "Y10")
    (pin "Y11")
    (pin "Y12")
    (pin "Y13")
    (pin "Y7")
    (pin "Y8")
    (pin "AA1")
    (pin "AA2")
    (pin "AA3")
    (pin "AA4")
    (pin "AA5")
    (pin "AB1")
    (pin "AB2")
    (pin "AB4")
    (pin "AB5")
    (pin "AB6")
    (pin "AC1")
    (pin "AC2")
    (pin "AC3")
    (pin "AC4")
    (pin "AC5")
    (pin "AC6")
    (pin "AD1")
    (pin "AD2")
    (pin "AD3")
    (pin "AD4")
    (pin "AD5")
    (pin "AD6")
    (pin "AE1")
    (pin "AE2")
    (pin "AE3")
    (pin "AE5")
    (pin "AE6")
    (pin "AF2")
    (pin "AF3")
    (pin "AF4")
    (pin "AF5")
    (pin "AF6")
    (pin "T7")
    (pin "U1")
    (pin "U2")
    (pin "U3")
    (pin "U4")
    (pin "U5")
    (pin "U6")
    (pin "U7")
    (pin "V1")
    (pin "V2")
    (pin "V3")
    (pin "V4")
    (pin "V6")
    (pin "W1")
    (pin "W3")
    (pin "W4")
    (pin "W5")
    (pin "W6")
    (pin "Y1")
    (pin "Y2")
    (pin "Y3")
    (pin "Y4")
    (pin "Y5")
    (pin "Y6")
    (pin "A3")
    (pin "A4")
    (pin "B1")
    (pin "B2")
    (pin "B5")
    (pin "B6")
    (pin "C3")
    (pin "C4")
    (pin "D1")
    (pin "D2")
    (pin "D5")
    (pin "D6")
    (pin "E3")
    (pin "E4")
    (pin "F1")
    (pin "F2")
    (pin "F5")
    (pin "F6")
    (pin "G3")
    (pin "G4")
    (pin "H1")
    (pin "H2")
    (pin "H5")
    (pin "H6")
    (pin "J3")
    (pin "J4")
    (pin "K1")
    (pin "K2")
    (pin "K5")
    (pin "K6")
    (pin "L3")
    (pin "L4")
    (pin "M1")
    (pin "M2")
    (pin "N3")
    (pin "N4")
    (pin "P1")
    (pin "P2")
    (pin "R3")
    (pin "R4")
    (pin "A1")
    (pin "A16")
    (pin "A2")
    (pin "A26")
    (pin "A5")
    (pin "A6")
    (pin "A7")
    (pin "AA16")
    (pin "AA26")
    (pin "AA6")
    (pin "AB13")
    (pin "AB23")
    (pin "AB3")
    (pin "AC10")
    (pin "AC20")
    (pin "AD17")
    (pin "AD7")
    (pin "AE14")
    (pin "AE24")
    (pin "AE4")
    (pin "AF1")
    (pin "AF11")
    (pin "AF21")
    (pin "B13")
    (pin "B23")
    (pin "B3")
    (pin "B4")
    (pin "B7")
    (pin "C1")
    (pin "C10")
    (pin "C2")
    (pin "C20")
    (pin "C5")
    (pin "C6")
    (pin "C7")
    (pin "D17")
    (pin "D3")
    (pin "D4")
    (pin "D7")
    (pin "E1")
    (pin "E14")
    (pin "E2")
    (pin "E24")
    (pin "E5")
    (pin "E6")
    (pin "E7")
    (pin "E8")
    (pin "F11")
    (pin "F21")
    (pin "F3")
    (pin "F4")
    (pin "F7")
    (pin "G1")
    (pin "G18")
    (pin "G2")
    (pin "G5")
    (pin "G6")
    (pin "G8")
    (pin "H15")
    (pin "H25")
    (pin "H3")
    (pin "H4")
    (pin "H7")
    (pin "J1")
    (pin "J12")
    (pin "J2")
    (pin "J22")
    (pin "J5")
    (pin "J6")
    (pin "J9")
    (pin "K10")
    (pin "K11")
    (pin "K12")
    (pin "K13")
    (pin "K14")
    (pin "K19")
    (pin "K3")
    (pin "K4")
    (pin "K7")
    (pin "K8")
    (pin "K9")
    (pin "L1")
    (pin "L10")
    (pin "L11")
    (pin "L12")
    (pin "L13")
    (pin "L14")
    (pin "L15")
    (pin "L16")
    (pin "L2")
    (pin "L26")
    (pin "L5")
    (pin "L6")
    (pin "L9")
    (pin "M10")
    (pin "M11")
    (pin "M12")
    (pin "M13")
    (pin "M14")
    (pin "M15")
    (pin "M23")
    (pin "M3")
    (pin "M4")
    (pin "M5")
    (pin "M6")
    (pin "M7")
    (pin "M8")
    (pin "M9")
    (pin "N1")
    (pin "N10")
    (pin "N13")
    (pin "N14")
    (pin "N15")
    (pin "N2")
    (pin "N20")
    (pin "N5")
    (pin "N6")
    (pin "N7")
    (pin "N9")
    (pin "P10")
    (pin "P13")
    (pin "P14")
    (pin "P15")
    (pin "P17")
    (pin "P3")
    (pin "P4")
    (pin "P8")
    (pin "P9")
    (pin "R1")
    (pin "R10")
    (pin "R13")
    (pin "R14")
    (pin "R15")
    (pin "R2")
    (pin "R24")
    (pin "R5")
    (pin "R8")
    (pin "R9")
    (pin "T1")
    (pin "T10")
    (pin "T11")
    (pin "T12")
    (pin "T13")
    (pin "T14")
    (pin "T15")
    (pin "T21")
    (pin "T3")
    (pin "T4")
    (pin "T8")
    (pin "T9")
    (pin "U10")
    (pin "U11")
    (pin "U12")
    (pin "U13")
    (pin "U14")
    (pin "U15")
    (pin "U18")
    (pin "U8")
    (pin "V15")
    (pin "V25")
    (pin "V5")
    (pin "W12")
    (pin "W2")
    (pin "W22")
    (pin "Y19")
    (pin "Y9")
    (pin "C8")
    (pin "G7")
    (pin "J7")
    (pin "L7")
    (pin "L8")
    (pin "N11")
    (pin "N12")
    (pin "N8")
    (pin "P11")
    (pin "P12")
    (pin "P5")
    (pin "P6")
    (pin "P7")
    (pin "R11")
    (pin "R12")
    (pin "R6")
    (pin "R7")
    (pin "T2")
    (pin "T5")
    (pin "T6")
    (instances
      (project "data-center-rdimm-ddr4-tester"
        (path ""
          (reference "U15") (unit 6)
        )
      )
    )
  )

  (symbol (lib_id "antmicroResistors0402:R_4k7_0402") (at 186.055 240.665 270) (unit 1)
    (in_bom yes) (on_board yes) (dnp no)
    (property "Reference" "R171" (at 184.785 241.935 90)
      (effects (font (size 1.524 1.524)) (justify right))
    )
    (property "Value" "R_4k7_0402" (at 173.355 260.985 0)
      (effects (font (size 1.27 1.27) (thickness 0.15)) (justify left bottom) hide)
    )
    (property "Footprint" "antmicro-footprints:R_0402_1005Metric" (at 170.815 260.985 0)
      (effects (font (size 1.27 1.27) (thickness 0.15)) (justify left bottom) hide)
    )
    (property "Datasheet" "https://www.bourns.com/docs/product-datasheets/cr.pdf" (at 168.275 260.985 0)
      (effects (font (size 1.27 1.27) (thickness 0.15)) (justify left bottom) hide)
    )
    (property "Manufacturer" "Bourns" (at 163.195 260.985 0)
      (effects (font (size 1.27 1.27) (thickness 0.15)) (justify left bottom) hide)
    )
    (property "MPN" "CR0402-FX-4701GLF" (at 165.735 260.985 0)
      (effects (font (size 1.27 1.27) (thickness 0.15)) (justify left bottom) hide)
    )
    (property "Val" "4k7" (at 184.785 245.11 90)
      (effects (font (size 1.27 1.27) (thickness 0.15)) (justify right))
    )
    (property "License" "Apache-2.0" (at 160.655 260.985 0)
      (effects (font (size 1.27 1.27) (thickness 0.15)) (justify left bottom) hide)
    )
    (property "Author" "Antmicro" (at 158.115 260.985 0)
      (effects (font (size 1.27 1.27) (thickness 0.15)) (justify left bottom) hide)
    )
    (property "Tolerance" "1%" (at 175.895 260.985 0)
      (effects (font (size 1.27 1.27)) (justify left bottom) hide)
    )
    (pin "1")
    (pin "2")
    (instances
      (project "data-center-rdimm-ddr4-tester"
        (path ""
          (reference "R171") (unit 1)
        )
      )
    )
  )

  (symbol (lib_id "antmicroResistors0402:R_4k7_0402") (at 189.23 240.665 270) (unit 1)
    (in_bom yes) (on_board yes) (dnp no)
    (property "Reference" "R172" (at 190.5 241.935 90)
      (effects (font (size 1.524 1.524)) (justify left))
    )
    (property "Value" "R_4k7_0402" (at 176.53 260.985 0)
      (effects (font (size 1.27 1.27) (thickness 0.15)) (justify left bottom) hide)
    )
    (property "Footprint" "antmicro-footprints:R_0402_1005Metric" (at 173.99 260.985 0)
      (effects (font (size 1.27 1.27) (thickness 0.15)) (justify left bottom) hide)
    )
    (property "Datasheet" "https://www.bourns.com/docs/product-datasheets/cr.pdf" (at 171.45 260.985 0)
      (effects (font (size 1.27 1.27) (thickness 0.15)) (justify left bottom) hide)
    )
    (property "Manufacturer" "Bourns" (at 166.37 260.985 0)
      (effects (font (size 1.27 1.27) (thickness 0.15)) (justify left bottom) hide)
    )
    (property "MPN" "CR0402-FX-4701GLF" (at 168.91 260.985 0)
      (effects (font (size 1.27 1.27) (thickness 0.15)) (justify left bottom) hide)
    )
    (property "Val" "4k7" (at 190.5 245.11 90)
      (effects (font (size 1.27 1.27) (thickness 0.15)) (justify left))
    )
    (property "License" "Apache-2.0" (at 163.83 260.985 0)
      (effects (font (size 1.27 1.27) (thickness 0.15)) (justify left bottom) hide)
    )
    (property "Author" "Antmicro" (at 161.29 260.985 0)
      (effects (font (size 1.27 1.27) (thickness 0.15)) (justify left bottom) hide)
    )
    (property "Tolerance" "1%" (at 179.07 260.985 0)
      (effects (font (size 1.27 1.27)) (justify left bottom) hide)
    )
    (pin "1")
    (pin "2")
    (instances
      (project "data-center-rdimm-ddr4-tester"
        (path ""
          (reference "R172") (unit 1)
        )
      )
    )
  )

  (symbol (lib_id "antmicroTestPoints:TP_1mm_SMD") (at 214.63 242.57 0) (mirror x) (unit 1)
    (in_bom yes) (on_board yes) (dnp no)
    (property "Reference" "TP12" (at 215.9 244.475 0)
      (effects (font (size 1.27 1.27)) (justify left))
    )
    (property "Value" "TP_1mm_SMD" (at 229.87 234.95 0)
      (effects (font (size 1.27 1.27) (thickness 0.15)) (justify left bottom) hide)
    )
    (property "Footprint" "antmicro-footprints:TP_SMD_1mm" (at 229.87 232.41 0)
      (effects (font (size 1.27 1.27) (thickness 0.15)) (justify left bottom) hide)
    )
    (property "Datasheet" "" (at 229.87 229.87 0)
      (effects (font (size 1.27 1.27) (thickness 0.15)) (justify left bottom) hide)
    )
    (property "MPN" "" (at 214.63 242.57 0)
      (effects (font (size 1.27 1.27)) hide)
    )
    (property "Manufacturer" "" (at 214.63 242.57 0)
      (effects (font (size 1.27 1.27)) hide)
    )
    (property "Author" "Antmicro" (at 229.87 227.33 0)
      (effects (font (size 1.27 1.27) (thickness 0.15)) (justify left bottom) hide)
    )
    (property "License" "Apache-2.0" (at 229.87 224.79 0)
      (effects (font (size 1.27 1.27) (thickness 0.15)) (justify left bottom) hide)
    )
    (pin "1")
    (instances
      (project "data-center-rdimm-ddr4-tester"
        (path ""
          (reference "TP12") (unit 1)
        )
      )
    )
  )

  (symbol (lib_id "antmicroResistors0402:R_0R_0402") (at 273.05 261.62 270) (unit 1)
    (in_bom yes) (on_board yes) (dnp no)
    (property "Reference" "R165" (at 273.685 260.985 90)
      (effects (font (size 1.524 1.524)) (justify left))
    )
    (property "Value" "R_0R_0402" (at 260.35 281.94 0)
      (effects (font (size 1.27 1.27) (thickness 0.15)) (justify left bottom) hide)
    )
    (property "Footprint" "antmicro-footprints:R_0402_1005Metric" (at 257.81 281.94 0)
      (effects (font (size 1.27 1.27) (thickness 0.15)) (justify left bottom) hide)
    )
    (property "Datasheet" "https://industrial.panasonic.com/cdbs/www-data/pdf/RDA0000/AOA0000C301.pdf" (at 255.27 281.94 0)
      (effects (font (size 1.27 1.27) (thickness 0.15)) (justify left bottom) hide)
    )
    (property "Manufacturer" "Panasonic" (at 250.19 281.94 0)
      (effects (font (size 1.27 1.27) (thickness 0.15)) (justify left bottom) hide)
    )
    (property "MPN" "ERJ2GE0R00X" (at 252.73 281.94 0)
      (effects (font (size 1.27 1.27) (thickness 0.15)) (justify left bottom) hide)
    )
    (property "Val" "0R" (at 274.32 264.16 90)
      (effects (font (size 1.27 1.27) (thickness 0.15)) (justify left))
    )
    (property "License" "Apache-2.0" (at 247.65 281.94 0)
      (effects (font (size 1.27 1.27) (thickness 0.15)) (justify left bottom) hide)
    )
    (property "Author" "Antmicro" (at 245.11 281.94 0)
      (effects (font (size 1.27 1.27) (thickness 0.15)) (justify left bottom) hide)
    )
    (property "Tolerance" "~" (at 262.89 281.94 0)
      (effects (font (size 1.27 1.27)) (justify left bottom) hide)
    )
    (property "Current" "1A" (at 242.57 281.94 0)
      (effects (font (size 1.27 1.27) (thickness 0.15)) (justify left bottom) hide)
    )
    (pin "1")
    (pin "2")
    (instances
      (project "data-center-rdimm-ddr4-tester"
        (path ""
          (reference "R165") (unit 1)
        )
      )
    )
  )

  (symbol (lib_id "antmicroResistors0402:R_0R_0402") (at 281.305 261.62 270) (unit 1)
    (in_bom yes) (on_board yes) (dnp no)
    (property "Reference" "R167" (at 281.94 260.985 90)
      (effects (font (size 1.524 1.524)) (justify left))
    )
    (property "Value" "R_0R_0402" (at 268.605 281.94 0)
      (effects (font (size 1.27 1.27) (thickness 0.15)) (justify left bottom) hide)
    )
    (property "Footprint" "antmicro-footprints:R_0402_1005Metric" (at 266.065 281.94 0)
      (effects (font (size 1.27 1.27) (thickness 0.15)) (justify left bottom) hide)
    )
    (property "Datasheet" "https://industrial.panasonic.com/cdbs/www-data/pdf/RDA0000/AOA0000C301.pdf" (at 263.525 281.94 0)
      (effects (font (size 1.27 1.27) (thickness 0.15)) (justify left bottom) hide)
    )
    (property "Manufacturer" "Panasonic" (at 258.445 281.94 0)
      (effects (font (size 1.27 1.27) (thickness 0.15)) (justify left bottom) hide)
    )
    (property "MPN" "ERJ2GE0R00X" (at 260.985 281.94 0)
      (effects (font (size 1.27 1.27) (thickness 0.15)) (justify left bottom) hide)
    )
    (property "Val" "0R" (at 282.575 264.16 90)
      (effects (font (size 1.27 1.27) (thickness 0.15)) (justify left))
    )
    (property "License" "Apache-2.0" (at 255.905 281.94 0)
      (effects (font (size 1.27 1.27) (thickness 0.15)) (justify left bottom) hide)
    )
    (property "Author" "Antmicro" (at 253.365 281.94 0)
      (effects (font (size 1.27 1.27) (thickness 0.15)) (justify left bottom) hide)
    )
    (property "Tolerance" "~" (at 271.145 281.94 0)
      (effects (font (size 1.27 1.27)) (justify left bottom) hide)
    )
    (property "Current" "1A" (at 250.825 281.94 0)
      (effects (font (size 1.27 1.27) (thickness 0.15)) (justify left bottom) hide)
    )
    (pin "1")
    (pin "2")
    (instances
      (project "data-center-rdimm-ddr4-tester"
        (path ""
          (reference "R167") (unit 1)
        )
      )
    )
  )

  (symbol (lib_id "antmicroResistors0402:R_0R_0402") (at 289.56 261.62 270) (unit 1)
    (in_bom yes) (on_board yes) (dnp no)
    (property "Reference" "R169" (at 290.195 260.985 90)
      (effects (font (size 1.524 1.524)) (justify left))
    )
    (property "Value" "R_0R_0402" (at 276.86 281.94 0)
      (effects (font (size 1.27 1.27) (thickness 0.15)) (justify left bottom) hide)
    )
    (property "Footprint" "antmicro-footprints:R_0402_1005Metric" (at 274.32 281.94 0)
      (effects (font (size 1.27 1.27) (thickness 0.15)) (justify left bottom) hide)
    )
    (property "Datasheet" "https://industrial.panasonic.com/cdbs/www-data/pdf/RDA0000/AOA0000C301.pdf" (at 271.78 281.94 0)
      (effects (font (size 1.27 1.27) (thickness 0.15)) (justify left bottom) hide)
    )
    (property "Manufacturer" "Panasonic" (at 266.7 281.94 0)
      (effects (font (size 1.27 1.27) (thickness 0.15)) (justify left bottom) hide)
    )
    (property "MPN" "ERJ2GE0R00X" (at 269.24 281.94 0)
      (effects (font (size 1.27 1.27) (thickness 0.15)) (justify left bottom) hide)
    )
    (property "Val" "0R" (at 290.83 264.16 90)
      (effects (font (size 1.27 1.27) (thickness 0.15)) (justify left))
    )
    (property "License" "Apache-2.0" (at 264.16 281.94 0)
      (effects (font (size 1.27 1.27) (thickness 0.15)) (justify left bottom) hide)
    )
    (property "Author" "Antmicro" (at 261.62 281.94 0)
      (effects (font (size 1.27 1.27) (thickness 0.15)) (justify left bottom) hide)
    )
    (property "Tolerance" "~" (at 279.4 281.94 0)
      (effects (font (size 1.27 1.27)) (justify left bottom) hide)
    )
    (property "Current" "1A" (at 259.08 281.94 0)
      (effects (font (size 1.27 1.27) (thickness 0.15)) (justify left bottom) hide)
    )
    (pin "1")
    (pin "2")
    (instances
      (project "data-center-rdimm-ddr4-tester"
        (path ""
          (reference "R169") (unit 1)
        )
      )
    )
  )

  (symbol (lib_id "antmicropower:GND") (at 273.05 266.7 0) (mirror y) (unit 1)
    (in_bom yes) (on_board yes) (dnp no) (fields_autoplaced)
    (property "Reference" "#PWR0146" (at 273.05 273.05 0)
      (effects (font (size 1.27 1.27)) hide)
    )
    (property "Value" "GND" (at 273.05 271.78 0)
      (effects (font (size 1.27 1.27)))
    )
    (property "Footprint" "" (at 273.05 266.7 0)
      (effects (font (size 1.27 1.27)) hide)
    )
    (property "Datasheet" "" (at 273.05 266.7 0)
      (effects (font (size 1.27 1.27)) hide)
    )
    (property "Author" "Antmicro" (at 264.16 274.32 0)
      (effects (font (size 1.27 1.27) (thickness 0.15)) (justify left bottom) hide)
    )
    (property "License" "Apache-2.0" (at 264.16 276.86 0)
      (effects (font (size 1.27 1.27) (thickness 0.15)) (justify left bottom) hide)
    )
    (pin "1")
    (instances
      (project "data-center-rdimm-ddr4-tester"
        (path ""
          (reference "#PWR0146") (unit 1)
        )
      )
    )
  )

  (symbol (lib_id "antmicropower:GND") (at 281.305 266.7 0) (mirror y) (unit 1)
    (in_bom yes) (on_board yes) (dnp no) (fields_autoplaced)
    (property "Reference" "#PWR0265" (at 281.305 273.05 0)
      (effects (font (size 1.27 1.27)) hide)
    )
    (property "Value" "GND" (at 281.305 271.78 0)
      (effects (font (size 1.27 1.27)))
    )
    (property "Footprint" "" (at 281.305 266.7 0)
      (effects (font (size 1.27 1.27)) hide)
    )
    (property "Datasheet" "" (at 281.305 266.7 0)
      (effects (font (size 1.27 1.27)) hide)
    )
    (property "Author" "Antmicro" (at 272.415 274.32 0)
      (effects (font (size 1.27 1.27) (thickness 0.15)) (justify left bottom) hide)
    )
    (property "License" "Apache-2.0" (at 272.415 276.86 0)
      (effects (font (size 1.27 1.27) (thickness 0.15)) (justify left bottom) hide)
    )
    (pin "1")
    (instances
      (project "data-center-rdimm-ddr4-tester"
        (path ""
          (reference "#PWR0265") (unit 1)
        )
      )
    )
  )

  (symbol (lib_id "antmicropower:GND") (at 289.56 266.7 0) (mirror y) (unit 1)
    (in_bom yes) (on_board yes) (dnp no) (fields_autoplaced)
    (property "Reference" "#PWR0266" (at 289.56 273.05 0)
      (effects (font (size 1.27 1.27)) hide)
    )
    (property "Value" "GND" (at 289.56 271.78 0)
      (effects (font (size 1.27 1.27)))
    )
    (property "Footprint" "" (at 289.56 266.7 0)
      (effects (font (size 1.27 1.27)) hide)
    )
    (property "Datasheet" "" (at 289.56 266.7 0)
      (effects (font (size 1.27 1.27)) hide)
    )
    (property "Author" "Antmicro" (at 280.67 274.32 0)
      (effects (font (size 1.27 1.27) (thickness 0.15)) (justify left bottom) hide)
    )
    (property "License" "Apache-2.0" (at 280.67 276.86 0)
      (effects (font (size 1.27 1.27) (thickness 0.15)) (justify left bottom) hide)
    )
    (pin "1")
    (instances
      (project "data-center-rdimm-ddr4-tester"
        (path ""
          (reference "#PWR0266") (unit 1)
        )
      )
    )
  )

  (symbol (lib_id "antmicroResistors0402:R_0R_0402") (at 273.05 247.65 270) (unit 1)
    (in_bom no) (on_board yes) (dnp yes)
    (property "Reference" "R164" (at 273.685 247.015 90)
      (effects (font (size 1.524 1.524)) (justify left))
    )
    (property "Value" "R_0R_0402" (at 260.35 267.97 0)
      (effects (font (size 1.27 1.27) (thickness 0.15)) (justify left bottom) hide)
    )
    (property "Footprint" "antmicro-footprints:R_0402_1005Metric" (at 257.81 267.97 0)
      (effects (font (size 1.27 1.27) (thickness 0.15)) (justify left bottom) hide)
    )
    (property "Datasheet" "https://industrial.panasonic.com/cdbs/www-data/pdf/RDA0000/AOA0000C301.pdf" (at 255.27 267.97 0)
      (effects (font (size 1.27 1.27) (thickness 0.15)) (justify left bottom) hide)
    )
    (property "Manufacturer" "Panasonic" (at 250.19 267.97 0)
      (effects (font (size 1.27 1.27) (thickness 0.15)) (justify left bottom) hide)
    )
    (property "MPN" "ERJ2GE0R00X" (at 252.73 267.97 0)
      (effects (font (size 1.27 1.27) (thickness 0.15)) (justify left bottom) hide)
    )
    (property "Val" "0R" (at 274.32 250.19 90)
      (effects (font (size 1.27 1.27) (thickness 0.15)) (justify left))
    )
    (property "License" "Apache-2.0" (at 247.65 267.97 0)
      (effects (font (size 1.27 1.27) (thickness 0.15)) (justify left bottom) hide)
    )
    (property "Author" "Antmicro" (at 245.11 267.97 0)
      (effects (font (size 1.27 1.27) (thickness 0.15)) (justify left bottom) hide)
    )
    (property "Tolerance" "~" (at 262.89 267.97 0)
      (effects (font (size 1.27 1.27)) (justify left bottom) hide)
    )
    (property "Current" "1A" (at 242.57 267.97 0)
      (effects (font (size 1.27 1.27) (thickness 0.15)) (justify left bottom) hide)
    )
    (property "DNP" "DNP" (at 273.05 250.19 0)
      (effects (font (size 1.27 1.27)))
    )
    (pin "1")
    (pin "2")
    (instances
      (project "data-center-rdimm-ddr4-tester"
        (path ""
          (reference "R164") (unit 1)
        )
      )
    )
  )

  (symbol (lib_id "antmicroResistors0402:R_0R_0402") (at 281.305 247.65 270) (unit 1)
    (in_bom no) (on_board yes) (dnp yes)
    (property "Reference" "R166" (at 281.94 247.015 90)
      (effects (font (size 1.524 1.524)) (justify left))
    )
    (property "Value" "R_0R_0402" (at 268.605 267.97 0)
      (effects (font (size 1.27 1.27) (thickness 0.15)) (justify left bottom) hide)
    )
    (property "Footprint" "antmicro-footprints:R_0402_1005Metric" (at 266.065 267.97 0)
      (effects (font (size 1.27 1.27) (thickness 0.15)) (justify left bottom) hide)
    )
    (property "Datasheet" "https://industrial.panasonic.com/cdbs/www-data/pdf/RDA0000/AOA0000C301.pdf" (at 263.525 267.97 0)
      (effects (font (size 1.27 1.27) (thickness 0.15)) (justify left bottom) hide)
    )
    (property "Manufacturer" "Panasonic" (at 258.445 267.97 0)
      (effects (font (size 1.27 1.27) (thickness 0.15)) (justify left bottom) hide)
    )
    (property "MPN" "ERJ2GE0R00X" (at 260.985 267.97 0)
      (effects (font (size 1.27 1.27) (thickness 0.15)) (justify left bottom) hide)
    )
    (property "Val" "0R" (at 282.575 250.19 90)
      (effects (font (size 1.27 1.27) (thickness 0.15)) (justify left))
    )
    (property "License" "Apache-2.0" (at 255.905 267.97 0)
      (effects (font (size 1.27 1.27) (thickness 0.15)) (justify left bottom) hide)
    )
    (property "Author" "Antmicro" (at 253.365 267.97 0)
      (effects (font (size 1.27 1.27) (thickness 0.15)) (justify left bottom) hide)
    )
    (property "Tolerance" "~" (at 271.145 267.97 0)
      (effects (font (size 1.27 1.27)) (justify left bottom) hide)
    )
    (property "Current" "1A" (at 250.825 267.97 0)
      (effects (font (size 1.27 1.27) (thickness 0.15)) (justify left bottom) hide)
    )
    (property "DNP" "DNP" (at 281.305 250.19 0)
      (effects (font (size 1.27 1.27)))
    )
    (pin "1")
    (pin "2")
    (instances
      (project "data-center-rdimm-ddr4-tester"
        (path ""
          (reference "R166") (unit 1)
        )
      )
    )
  )

  (symbol (lib_id "antmicroResistors0402:R_0R_0402") (at 289.56 247.65 270) (unit 1)
    (in_bom no) (on_board yes) (dnp yes)
    (property "Reference" "R168" (at 290.195 247.015 90)
      (effects (font (size 1.524 1.524)) (justify left))
    )
    (property "Value" "R_0R_0402" (at 276.86 267.97 0)
      (effects (font (size 1.27 1.27) (thickness 0.15)) (justify left bottom) hide)
    )
    (property "Footprint" "antmicro-footprints:R_0402_1005Metric" (at 274.32 267.97 0)
      (effects (font (size 1.27 1.27) (thickness 0.15)) (justify left bottom) hide)
    )
    (property "Datasheet" "https://industrial.panasonic.com/cdbs/www-data/pdf/RDA0000/AOA0000C301.pdf" (at 271.78 267.97 0)
      (effects (font (size 1.27 1.27) (thickness 0.15)) (justify left bottom) hide)
    )
    (property "Manufacturer" "Panasonic" (at 266.7 267.97 0)
      (effects (font (size 1.27 1.27) (thickness 0.15)) (justify left bottom) hide)
    )
    (property "MPN" "ERJ2GE0R00X" (at 269.24 267.97 0)
      (effects (font (size 1.27 1.27) (thickness 0.15)) (justify left bottom) hide)
    )
    (property "Val" "0R" (at 290.83 250.19 90)
      (effects (font (size 1.27 1.27) (thickness 0.15)) (justify left))
    )
    (property "License" "Apache-2.0" (at 264.16 267.97 0)
      (effects (font (size 1.27 1.27) (thickness 0.15)) (justify left bottom) hide)
    )
    (property "Author" "Antmicro" (at 261.62 267.97 0)
      (effects (font (size 1.27 1.27) (thickness 0.15)) (justify left bottom) hide)
    )
    (property "Tolerance" "~" (at 279.4 267.97 0)
      (effects (font (size 1.27 1.27)) (justify left bottom) hide)
    )
    (property "Current" "1A" (at 259.08 267.97 0)
      (effects (font (size 1.27 1.27) (thickness 0.15)) (justify left bottom) hide)
    )
    (property "DNP" "DNP" (at 289.56 250.19 0)
      (effects (font (size 1.27 1.27)))
    )
    (pin "1")
    (pin "2")
    (instances
      (project "data-center-rdimm-ddr4-tester"
        (path ""
          (reference "R168") (unit 1)
        )
      )
    )
  )

  (symbol (lib_id "antmicropower:GND") (at 343.535 243.84 0) (mirror y) (unit 1)
    (in_bom yes) (on_board yes) (dnp no) (fields_autoplaced)
    (property "Reference" "#PWR0128" (at 343.535 250.19 0)
      (effects (font (size 1.27 1.27)) hide)
    )
    (property "Value" "GND" (at 343.535 248.285 0)
      (effects (font (size 1.27 1.27)))
    )
    (property "Footprint" "" (at 343.535 243.84 0)
      (effects (font (size 1.27 1.27)) hide)
    )
    (property "Datasheet" "" (at 343.535 243.84 0)
      (effects (font (size 1.27 1.27)) hide)
    )
    (property "Author" "Antmicro" (at 334.645 251.46 0)
      (effects (font (size 1.27 1.27) (thickness 0.15)) (justify left bottom) hide)
    )
    (property "License" "Apache-2.0" (at 334.645 254 0)
      (effects (font (size 1.27 1.27) (thickness 0.15)) (justify left bottom) hide)
    )
    (pin "1")
    (instances
      (project "data-center-rdimm-ddr4-tester"
        (path ""
          (reference "#PWR0128") (unit 1)
        )
      )
    )
  )

  (symbol (lib_id "antmicropower:GND") (at 336.55 243.84 0) (mirror y) (unit 1)
    (in_bom yes) (on_board yes) (dnp no) (fields_autoplaced)
    (property "Reference" "#PWR0143" (at 336.55 250.19 0)
      (effects (font (size 1.27 1.27)) hide)
    )
    (property "Value" "GND" (at 336.55 248.285 0)
      (effects (font (size 1.27 1.27)))
    )
    (property "Footprint" "" (at 336.55 243.84 0)
      (effects (font (size 1.27 1.27)) hide)
    )
    (property "Datasheet" "" (at 336.55 243.84 0)
      (effects (font (size 1.27 1.27)) hide)
    )
    (property "Author" "Antmicro" (at 327.66 251.46 0)
      (effects (font (size 1.27 1.27) (thickness 0.15)) (justify left bottom) hide)
    )
    (property "License" "Apache-2.0" (at 327.66 254 0)
      (effects (font (size 1.27 1.27) (thickness 0.15)) (justify left bottom) hide)
    )
    (pin "1")
    (instances
      (project "data-center-rdimm-ddr4-tester"
        (path ""
          (reference "#PWR0143") (unit 1)
        )
      )
    )
  )

  (symbol (lib_id "antmicroCapacitors0402:C_100n_0402") (at 343.535 238.76 90) (mirror x) (unit 1)
    (in_bom yes) (on_board yes) (dnp no)
    (property "Reference" "C146" (at 344.17 239.395 90)
      (effects (font (size 1.524 1.524)) (justify right))
    )
    (property "Value" "C_100n_0402" (at 353.695 259.08 0)
      (effects (font (size 1.27 1.27) (thickness 0.15)) (justify left bottom) hide)
    )
    (property "Footprint" "antmicro-footprints:C_0402_1005Metric" (at 356.235 259.08 0)
      (effects (font (size 1.27 1.27) (thickness 0.15)) (justify left bottom) hide)
    )
    (property "Datasheet" "https://search.murata.co.jp/Ceramy/image/img/A01X/G101/ENG/GRM155R61H104KE14-01.pdf" (at 358.775 259.08 0)
      (effects (font (size 1.27 1.27) (thickness 0.15)) (justify left bottom) hide)
    )
    (property "Manufacturer" "Murata" (at 363.855 259.08 0)
      (effects (font (size 1.27 1.27) (thickness 0.15)) (justify left bottom) hide)
    )
    (property "MPN" "GRM155R61H104KE14D" (at 361.315 259.08 0)
      (effects (font (size 1.27 1.27) (thickness 0.15)) (justify left bottom) hide)
    )
    (property "Val" "100n" (at 344.17 243.205 90)
      (effects (font (size 1.27 1.27) (thickness 0.15)) (justify right))
    )
    (property "License" "Apache-2.0" (at 366.395 259.08 0)
      (effects (font (size 1.27 1.27) (thickness 0.15)) (justify left bottom) hide)
    )
    (property "Author" "Antmicro" (at 368.935 259.08 0)
      (effects (font (size 1.27 1.27) (thickness 0.15)) (justify left bottom) hide)
    )
    (property "Voltage" "50V" (at 371.475 259.08 0)
      (effects (font (size 1.27 1.27)) (justify left bottom) hide)
    )
    (property "Dielectric" "X5R" (at 374.015 259.08 0)
      (effects (font (size 1.27 1.27)) (justify left bottom) hide)
    )
    (pin "1")
    (pin "2")
    (instances
      (project "data-center-rdimm-ddr4-tester"
        (path ""
          (reference "C146") (unit 1)
        )
      )
    )
  )

  (symbol (lib_id "antmicroCapacitors0402:C_100n_0402") (at 336.55 238.76 90) (mirror x) (unit 1)
    (in_bom yes) (on_board yes) (dnp no)
    (property "Reference" "C18" (at 337.185 239.395 90)
      (effects (font (size 1.524 1.524)) (justify right))
    )
    (property "Value" "C_100n_0402" (at 346.71 259.08 0)
      (effects (font (size 1.27 1.27) (thickness 0.15)) (justify left bottom) hide)
    )
    (property "Footprint" "antmicro-footprints:C_0402_1005Metric" (at 349.25 259.08 0)
      (effects (font (size 1.27 1.27) (thickness 0.15)) (justify left bottom) hide)
    )
    (property "Datasheet" "https://search.murata.co.jp/Ceramy/image/img/A01X/G101/ENG/GRM155R61H104KE14-01.pdf" (at 351.79 259.08 0)
      (effects (font (size 1.27 1.27) (thickness 0.15)) (justify left bottom) hide)
    )
    (property "Manufacturer" "Murata" (at 356.87 259.08 0)
      (effects (font (size 1.27 1.27) (thickness 0.15)) (justify left bottom) hide)
    )
    (property "MPN" "GRM155R61H104KE14D" (at 354.33 259.08 0)
      (effects (font (size 1.27 1.27) (thickness 0.15)) (justify left bottom) hide)
    )
    (property "Val" "100n" (at 337.185 243.205 90)
      (effects (font (size 1.27 1.27) (thickness 0.15)) (justify right))
    )
    (property "License" "Apache-2.0" (at 359.41 259.08 0)
      (effects (font (size 1.27 1.27) (thickness 0.15)) (justify left bottom) hide)
    )
    (property "Author" "Antmicro" (at 361.95 259.08 0)
      (effects (font (size 1.27 1.27) (thickness 0.15)) (justify left bottom) hide)
    )
    (property "Voltage" "50V" (at 364.49 259.08 0)
      (effects (font (size 1.27 1.27)) (justify left bottom) hide)
    )
    (property "Dielectric" "X5R" (at 367.03 259.08 0)
      (effects (font (size 1.27 1.27)) (justify left bottom) hide)
    )
    (pin "1")
    (pin "2")
    (instances
      (project "data-center-rdimm-ddr4-tester"
        (path ""
          (reference "C18") (unit 1)
        )
      )
    )
  )

  (symbol (lib_id "antmicropower:GND") (at 326.39 243.84 0) (mirror y) (unit 1)
    (in_bom yes) (on_board yes) (dnp no) (fields_autoplaced)
    (property "Reference" "#PWR0144" (at 326.39 250.19 0)
      (effects (font (size 1.27 1.27)) hide)
    )
    (property "Value" "GND" (at 326.39 248.285 0)
      (effects (font (size 1.27 1.27)))
    )
    (property "Footprint" "" (at 326.39 243.84 0)
      (effects (font (size 1.27 1.27)) hide)
    )
    (property "Datasheet" "" (at 326.39 243.84 0)
      (effects (font (size 1.27 1.27)) hide)
    )
    (property "Author" "Antmicro" (at 317.5 251.46 0)
      (effects (font (size 1.27 1.27) (thickness 0.15)) (justify left bottom) hide)
    )
    (property "License" "Apache-2.0" (at 317.5 254 0)
      (effects (font (size 1.27 1.27) (thickness 0.15)) (justify left bottom) hide)
    )
    (pin "1")
    (instances
      (project "data-center-rdimm-ddr4-tester"
        (path ""
          (reference "#PWR0144") (unit 1)
        )
      )
    )
  )

  (symbol (lib_id "antmicroResistors0603:R_1k_0603") (at 326.39 238.76 270) (unit 1)
    (in_bom yes) (on_board yes) (dnp no) (fields_autoplaced)
    (property "Reference" "R66" (at 328.295 240.03 90)
      (effects (font (size 1.524 1.524)) (justify left))
    )
    (property "Value" "R_1k_0603" (at 313.69 259.08 0)
      (effects (font (size 1.27 1.27) (thickness 0.15)) (justify left bottom) hide)
    )
    (property "Footprint" "antmicro-footprints:R_0603_1608Metric" (at 311.15 259.08 0)
      (effects (font (size 1.27 1.27) (thickness 0.15)) (justify left bottom) hide)
    )
    (property "Datasheet" "https://www.bourns.com/docs/product-datasheets/cr.pdf" (at 308.61 259.08 0)
      (effects (font (size 1.27 1.27) (thickness 0.15)) (justify left bottom) hide)
    )
    (property "Manufacturer" "Bourns" (at 303.53 259.08 0)
      (effects (font (size 1.27 1.27) (thickness 0.15)) (justify left bottom) hide)
    )
    (property "MPN" "CR0603-FX-1001ELF" (at 306.07 259.08 0)
      (effects (font (size 1.27 1.27) (thickness 0.15)) (justify left bottom) hide)
    )
    (property "Val" "1k" (at 328.295 243.2049 90)
      (effects (font (size 1.27 1.27) (thickness 0.15)) (justify left))
    )
    (property "License" "Apache-2.0" (at 300.99 259.08 0)
      (effects (font (size 1.27 1.27) (thickness 0.15)) (justify left bottom) hide)
    )
    (property "Author" "Antmicro" (at 298.45 259.08 0)
      (effects (font (size 1.27 1.27) (thickness 0.15)) (justify left bottom) hide)
    )
    (property "Tolerance" "1%" (at 316.23 259.08 0)
      (effects (font (size 1.27 1.27)) (justify left bottom) hide)
    )
    (pin "1")
    (pin "2")
    (instances
      (project "data-center-rdimm-ddr4-tester"
        (path ""
          (reference "R66") (unit 1)
        )
      )
    )
  )

  (symbol (lib_id "antmicroResistors0603:R_1k_0603") (at 326.39 228.6 270) (unit 1)
    (in_bom yes) (on_board yes) (dnp no) (fields_autoplaced)
    (property "Reference" "R65" (at 328.295 229.87 90)
      (effects (font (size 1.524 1.524)) (justify left))
    )
    (property "Value" "R_1k_0603" (at 313.69 248.92 0)
      (effects (font (size 1.27 1.27) (thickness 0.15)) (justify left bottom) hide)
    )
    (property "Footprint" "antmicro-footprints:R_0603_1608Metric" (at 311.15 248.92 0)
      (effects (font (size 1.27 1.27) (thickness 0.15)) (justify left bottom) hide)
    )
    (property "Datasheet" "https://www.bourns.com/docs/product-datasheets/cr.pdf" (at 308.61 248.92 0)
      (effects (font (size 1.27 1.27) (thickness 0.15)) (justify left bottom) hide)
    )
    (property "Manufacturer" "Bourns" (at 303.53 248.92 0)
      (effects (font (size 1.27 1.27) (thickness 0.15)) (justify left bottom) hide)
    )
    (property "MPN" "CR0603-FX-1001ELF" (at 306.07 248.92 0)
      (effects (font (size 1.27 1.27) (thickness 0.15)) (justify left bottom) hide)
    )
    (property "Val" "1k" (at 328.295 233.0449 90)
      (effects (font (size 1.27 1.27) (thickness 0.15)) (justify left))
    )
    (property "License" "Apache-2.0" (at 300.99 248.92 0)
      (effects (font (size 1.27 1.27) (thickness 0.15)) (justify left bottom) hide)
    )
    (property "Author" "Antmicro" (at 298.45 248.92 0)
      (effects (font (size 1.27 1.27) (thickness 0.15)) (justify left bottom) hide)
    )
    (property "Tolerance" "1%" (at 316.23 248.92 0)
      (effects (font (size 1.27 1.27)) (justify left bottom) hide)
    )
    (pin "1")
    (pin "2")
    (instances
      (project "data-center-rdimm-ddr4-tester"
        (path ""
          (reference "R65") (unit 1)
        )
      )
    )
  )

  (symbol (lib_id "antmicropower:GND") (at 217.17 254.635 0) (unit 1)
    (in_bom yes) (on_board yes) (dnp no) (fields_autoplaced)
    (property "Reference" "#PWR0145" (at 217.17 260.985 0)
      (effects (font (size 1.27 1.27)) hide)
    )
    (property "Value" "GND" (at 217.17 259.08 0)
      (effects (font (size 1.27 1.27)))
    )
    (property "Footprint" "" (at 217.17 254.635 0)
      (effects (font (size 1.27 1.27)) hide)
    )
    (property "Datasheet" "" (at 217.17 254.635 0)
      (effects (font (size 1.27 1.27)) hide)
    )
    (property "Author" "Antmicro" (at 226.06 262.255 0)
      (effects (font (size 1.27 1.27) (thickness 0.15)) (justify left bottom) hide)
    )
    (property "License" "Apache-2.0" (at 226.06 264.795 0)
      (effects (font (size 1.27 1.27) (thickness 0.15)) (justify left bottom) hide)
    )
    (pin "1")
    (instances
      (project "data-center-rdimm-ddr4-tester"
        (path ""
          (reference "#PWR0145") (unit 1)
        )
      )
    )
  )

  (symbol (lib_id "antmicropower:GND") (at 222.885 274.32 0) (mirror y) (unit 1)
    (in_bom yes) (on_board yes) (dnp no) (fields_autoplaced)
    (property "Reference" "#PWR024" (at 222.885 280.67 0)
      (effects (font (size 1.27 1.27)) hide)
    )
    (property "Value" "GND" (at 222.885 279.4 0)
      (effects (font (size 1.27 1.27)))
    )
    (property "Footprint" "" (at 222.885 274.32 0)
      (effects (font (size 1.27 1.27)) hide)
    )
    (property "Datasheet" "" (at 222.885 274.32 0)
      (effects (font (size 1.27 1.27)) hide)
    )
    (property "Author" "Antmicro" (at 213.995 281.94 0)
      (effects (font (size 1.27 1.27) (thickness 0.15)) (justify left bottom) hide)
    )
    (property "License" "Apache-2.0" (at 213.995 284.48 0)
      (effects (font (size 1.27 1.27) (thickness 0.15)) (justify left bottom) hide)
    )
    (pin "1")
    (instances
      (project "data-center-rdimm-ddr4-tester"
        (path ""
          (reference "#PWR024") (unit 1)
        )
      )
    )
  )

  (symbol (lib_id "antmicroCapacitors0402:C_100n_0402") (at 222.885 269.24 90) (mirror x) (unit 1)
    (in_bom yes) (on_board yes) (dnp no) (fields_autoplaced)
    (property "Reference" "C206" (at 225.425 270.5163 90)
      (effects (font (size 1.524 1.524)) (justify right))
    )
    (property "Value" "C_100n_0402" (at 233.045 289.56 0)
      (effects (font (size 1.27 1.27) (thickness 0.15)) (justify left bottom) hide)
    )
    (property "Footprint" "antmicro-footprints:C_0402_1005Metric" (at 235.585 289.56 0)
      (effects (font (size 1.27 1.27) (thickness 0.15)) (justify left bottom) hide)
    )
    (property "Datasheet" "https://search.murata.co.jp/Ceramy/image/img/A01X/G101/ENG/GRM155R61H104KE14-01.pdf" (at 238.125 289.56 0)
      (effects (font (size 1.27 1.27) (thickness 0.15)) (justify left bottom) hide)
    )
    (property "Manufacturer" "Murata" (at 243.205 289.56 0)
      (effects (font (size 1.27 1.27) (thickness 0.15)) (justify left bottom) hide)
    )
    (property "MPN" "GRM155R61H104KE14D" (at 240.665 289.56 0)
      (effects (font (size 1.27 1.27) (thickness 0.15)) (justify left bottom) hide)
    )
    (property "Val" "100n" (at 225.425 273.6912 90)
      (effects (font (size 1.27 1.27) (thickness 0.15)) (justify right))
    )
    (property "License" "Apache-2.0" (at 245.745 289.56 0)
      (effects (font (size 1.27 1.27) (thickness 0.15)) (justify left bottom) hide)
    )
    (property "Author" "Antmicro" (at 248.285 289.56 0)
      (effects (font (size 1.27 1.27) (thickness 0.15)) (justify left bottom) hide)
    )
    (property "Voltage" "50V" (at 250.825 289.56 0)
      (effects (font (size 1.27 1.27)) (justify left bottom) hide)
    )
    (property "Dielectric" "X5R" (at 253.365 289.56 0)
      (effects (font (size 1.27 1.27)) (justify left bottom) hide)
    )
    (pin "1")
    (pin "2")
    (instances
      (project "data-center-rdimm-ddr4-tester"
        (path ""
          (reference "C206") (unit 1)
        )
      )
    )
  )

  (symbol (lib_id "antmicropower:GND") (at 236.22 274.32 0) (mirror y) (unit 1)
    (in_bom yes) (on_board yes) (dnp no) (fields_autoplaced)
    (property "Reference" "#PWR033" (at 236.22 280.67 0)
      (effects (font (size 1.27 1.27)) hide)
    )
    (property "Value" "GND" (at 236.22 279.4 0)
      (effects (font (size 1.27 1.27)))
    )
    (property "Footprint" "" (at 236.22 274.32 0)
      (effects (font (size 1.27 1.27)) hide)
    )
    (property "Datasheet" "" (at 236.22 274.32 0)
      (effects (font (size 1.27 1.27)) hide)
    )
    (property "Author" "Antmicro" (at 227.33 281.94 0)
      (effects (font (size 1.27 1.27) (thickness 0.15)) (justify left bottom) hide)
    )
    (property "License" "Apache-2.0" (at 227.33 284.48 0)
      (effects (font (size 1.27 1.27) (thickness 0.15)) (justify left bottom) hide)
    )
    (pin "1")
    (instances
      (project "data-center-rdimm-ddr4-tester"
        (path ""
          (reference "#PWR033") (unit 1)
        )
      )
    )
  )

  (symbol (lib_id "antmicroCapacitors0402:C_100n_0402") (at 236.22 269.24 90) (mirror x) (unit 1)
    (in_bom yes) (on_board yes) (dnp no) (fields_autoplaced)
    (property "Reference" "C207" (at 239.395 270.5163 90)
      (effects (font (size 1.524 1.524)) (justify right))
    )
    (property "Value" "C_100n_0402" (at 246.38 289.56 0)
      (effects (font (size 1.27 1.27) (thickness 0.15)) (justify left bottom) hide)
    )
    (property "Footprint" "antmicro-footprints:C_0402_1005Metric" (at 248.92 289.56 0)
      (effects (font (size 1.27 1.27) (thickness 0.15)) (justify left bottom) hide)
    )
    (property "Datasheet" "https://search.murata.co.jp/Ceramy/image/img/A01X/G101/ENG/GRM155R61H104KE14-01.pdf" (at 251.46 289.56 0)
      (effects (font (size 1.27 1.27) (thickness 0.15)) (justify left bottom) hide)
    )
    (property "Manufacturer" "Murata" (at 256.54 289.56 0)
      (effects (font (size 1.27 1.27) (thickness 0.15)) (justify left bottom) hide)
    )
    (property "MPN" "GRM155R61H104KE14D" (at 254 289.56 0)
      (effects (font (size 1.27 1.27) (thickness 0.15)) (justify left bottom) hide)
    )
    (property "Val" "100n" (at 239.395 273.6912 90)
      (effects (font (size 1.27 1.27) (thickness 0.15)) (justify right))
    )
    (property "License" "Apache-2.0" (at 259.08 289.56 0)
      (effects (font (size 1.27 1.27) (thickness 0.15)) (justify left bottom) hide)
    )
    (property "Author" "Antmicro" (at 261.62 289.56 0)
      (effects (font (size 1.27 1.27) (thickness 0.15)) (justify left bottom) hide)
    )
    (property "Voltage" "50V" (at 264.16 289.56 0)
      (effects (font (size 1.27 1.27)) (justify left bottom) hide)
    )
    (property "Dielectric" "X5R" (at 266.7 289.56 0)
      (effects (font (size 1.27 1.27)) (justify left bottom) hide)
    )
    (pin "1")
    (pin "2")
    (instances
      (project "data-center-rdimm-ddr4-tester"
        (path ""
          (reference "C207") (unit 1)
        )
      )
    )
  )

  (symbol (lib_id "antmicropower:GND") (at 388.62 243.205 0) (mirror y) (unit 1)
    (in_bom yes) (on_board yes) (dnp no) (fields_autoplaced)
    (property "Reference" "#PWR0267" (at 388.62 249.555 0)
      (effects (font (size 1.27 1.27)) hide)
    )
    (property "Value" "GND" (at 388.62 248.285 0)
      (effects (font (size 1.27 1.27)))
    )
    (property "Footprint" "" (at 388.62 243.205 0)
      (effects (font (size 1.27 1.27)) hide)
    )
    (property "Datasheet" "" (at 388.62 243.205 0)
      (effects (font (size 1.27 1.27)) hide)
    )
    (property "Author" "Antmicro" (at 379.73 250.825 0)
      (effects (font (size 1.27 1.27) (thickness 0.15)) (justify left bottom) hide)
    )
    (property "License" "Apache-2.0" (at 379.73 253.365 0)
      (effects (font (size 1.27 1.27) (thickness 0.15)) (justify left bottom) hide)
    )
    (pin "1")
    (instances
      (project "data-center-rdimm-ddr4-tester"
        (path ""
          (reference "#PWR0267") (unit 1)
        )
      )
    )
  )

  (symbol (lib_id "antmicroResistors0402:R_4k7_0402") (at 178.435 268.605 0) (unit 1)
    (in_bom yes) (on_board yes) (dnp no)
    (property "Reference" "R170" (at 180.975 264.16 0)
      (effects (font (size 1.524 1.524)))
    )
    (property "Value" "R_4k7_0402" (at 198.755 281.305 0)
      (effects (font (size 1.27 1.27) (thickness 0.15)) (justify left bottom) hide)
    )
    (property "Footprint" "antmicro-footprints:R_0402_1005Metric" (at 198.755 283.845 0)
      (effects (font (size 1.27 1.27) (thickness 0.15)) (justify left bottom) hide)
    )
    (property "Datasheet" "https://www.bourns.com/docs/product-datasheets/cr.pdf" (at 198.755 286.385 0)
      (effects (font (size 1.27 1.27) (thickness 0.15)) (justify left bottom) hide)
    )
    (property "Manufacturer" "Bourns" (at 198.755 291.465 0)
      (effects (font (size 1.27 1.27) (thickness 0.15)) (justify left bottom) hide)
    )
    (property "MPN" "CR0402-FX-4701GLF" (at 198.755 288.925 0)
      (effects (font (size 1.27 1.27) (thickness 0.15)) (justify left bottom) hide)
    )
    (property "Val" "4k7" (at 180.975 266.065 0)
      (effects (font (size 1.27 1.27) (thickness 0.15)))
    )
    (property "License" "Apache-2.0" (at 198.755 294.005 0)
      (effects (font (size 1.27 1.27) (thickness 0.15)) (justify left bottom) hide)
    )
    (property "Author" "Antmicro" (at 198.755 296.545 0)
      (effects (font (size 1.27 1.27) (thickness 0.15)) (justify left bottom) hide)
    )
    (property "Tolerance" "1%" (at 198.755 278.765 0)
      (effects (font (size 1.27 1.27)) (justify left bottom) hide)
    )
    (pin "1")
    (pin "2")
    (instances
      (project "data-center-rdimm-ddr4-tester"
        (path ""
          (reference "R170") (unit 1)
        )
      )
    )
  )

  (symbol (lib_id "antmicropower:GND") (at 99.695 248.285 0) (unit 1)
    (in_bom yes) (on_board yes) (dnp no) (fields_autoplaced)
    (property "Reference" "#PWR0141" (at 99.695 254.635 0)
      (effects (font (size 1.27 1.27)) hide)
    )
    (property "Value" "GND" (at 99.695 253.365 0)
      (effects (font (size 1.27 1.27)))
    )
    (property "Footprint" "" (at 99.695 248.285 0)
      (effects (font (size 1.27 1.27)) hide)
    )
    (property "Datasheet" "" (at 99.695 248.285 0)
      (effects (font (size 1.27 1.27)) hide)
    )
    (property "Author" "Antmicro" (at 108.585 255.905 0)
      (effects (font (size 1.27 1.27) (thickness 0.15)) (justify left bottom) hide)
    )
    (property "License" "Apache-2.0" (at 108.585 258.445 0)
      (effects (font (size 1.27 1.27) (thickness 0.15)) (justify left bottom) hide)
    )
    (pin "1")
    (instances
      (project "data-center-rdimm-ddr4-tester"
        (path ""
          (reference "#PWR0141") (unit 1)
        )
      )
    )
  )

  (symbol (lib_id "antmicroCapacitors0402:C_100n_0402") (at 74.295 243.205 90) (mirror x) (unit 1)
    (in_bom yes) (on_board yes) (dnp no) (fields_autoplaced)
    (property "Reference" "C145" (at 71.755 244.4813 90)
      (effects (font (size 1.524 1.524)) (justify left))
    )
    (property "Value" "C_100n_0402" (at 84.455 263.525 0)
      (effects (font (size 1.27 1.27) (thickness 0.15)) (justify left bottom) hide)
    )
    (property "Footprint" "antmicro-footprints:C_0402_1005Metric" (at 86.995 263.525 0)
      (effects (font (size 1.27 1.27) (thickness 0.15)) (justify left bottom) hide)
    )
    (property "Datasheet" "https://search.murata.co.jp/Ceramy/image/img/A01X/G101/ENG/GRM155R61H104KE14-01.pdf" (at 89.535 263.525 0)
      (effects (font (size 1.27 1.27) (thickness 0.15)) (justify left bottom) hide)
    )
    (property "Manufacturer" "Murata" (at 94.615 263.525 0)
      (effects (font (size 1.27 1.27) (thickness 0.15)) (justify left bottom) hide)
    )
    (property "MPN" "GRM155R61H104KE14D" (at 92.075 263.525 0)
      (effects (font (size 1.27 1.27) (thickness 0.15)) (justify left bottom) hide)
    )
    (property "Val" "100n" (at 71.755 247.6562 90)
      (effects (font (size 1.27 1.27) (thickness 0.15)) (justify left))
    )
    (property "License" "Apache-2.0" (at 97.155 263.525 0)
      (effects (font (size 1.27 1.27) (thickness 0.15)) (justify left bottom) hide)
    )
    (property "Author" "Antmicro" (at 99.695 263.525 0)
      (effects (font (size 1.27 1.27) (thickness 0.15)) (justify left bottom) hide)
    )
    (property "Voltage" "50V" (at 102.235 263.525 0)
      (effects (font (size 1.27 1.27)) (justify left bottom) hide)
    )
    (property "Dielectric" "X5R" (at 104.775 263.525 0)
      (effects (font (size 1.27 1.27)) (justify left bottom) hide)
    )
    (pin "1")
    (pin "2")
    (instances
      (project "data-center-rdimm-ddr4-tester"
        (path ""
          (reference "C145") (unit 1)
        )
      )
    )
  )

  (symbol (lib_id "antmicropower:GND") (at 74.295 248.285 0) (mirror y) (unit 1)
    (in_bom yes) (on_board yes) (dnp no) (fields_autoplaced)
    (property "Reference" "#PWR0142" (at 74.295 254.635 0)
      (effects (font (size 1.27 1.27)) hide)
    )
    (property "Value" "GND" (at 74.295 253.365 0)
      (effects (font (size 1.27 1.27)))
    )
    (property "Footprint" "" (at 74.295 248.285 0)
      (effects (font (size 1.27 1.27)) hide)
    )
    (property "Datasheet" "" (at 74.295 248.285 0)
      (effects (font (size 1.27 1.27)) hide)
    )
    (property "Author" "Antmicro" (at 65.405 255.905 0)
      (effects (font (size 1.27 1.27) (thickness 0.15)) (justify left bottom) hide)
    )
    (property "License" "Apache-2.0" (at 65.405 258.445 0)
      (effects (font (size 1.27 1.27) (thickness 0.15)) (justify left bottom) hide)
    )
    (pin "1")
    (instances
      (project "data-center-rdimm-ddr4-tester"
        (path ""
          (reference "#PWR0142") (unit 1)
        )
      )
    )
  )

  (symbol (lib_id "data-center-rdimm-ddr4-tester:Oscillator_SMD_100MHz_ASFLMB") (at 80.645 241.3 0) (unit 1)
    (in_bom yes) (on_board yes) (dnp no)
    (property "Reference" "U1" (at 88.9 235.585 0)
      (effects (font (size 1.524 1.524)))
    )
    (property "Value" "Oscillator_SMD_100MHz_ASFLMB" (at 88.9 235.585 0)
      (effects (font (size 1.27 1.27) (thickness 0.15)) hide)
    )
    (property "Footprint" "data-center-rdimm-ddr4-tester-footprints:Oscillator_SMD_Abracon_ASFLMB_5x3.2x0.85mm" (at 121.285 248.92 0)
      (effects (font (size 1.27 1.27) (thickness 0.15)) (justify left bottom) hide)
    )
    (property "Datasheet" "https://abracon.com/Oscillators/ASFLMB.pdf" (at 121.285 251.46 0)
      (effects (font (size 1.27 1.27) (thickness 0.15)) (justify left bottom) hide)
    )
    (property "MPN" "ASFLMB-100.000MHZ-XY-T" (at 88.9 237.49 0)
      (effects (font (size 1.27 1.27) (thickness 0.15)))
    )
    (property "Manufacturer" "Abracon" (at 121.285 254 0)
      (effects (font (size 1.27 1.27) (thickness 0.15)) (justify left bottom) hide)
    )
    (property "Author" "Antmicro" (at 121.285 259.08 0)
      (effects (font (size 1.27 1.27) (thickness 0.15)) (justify left bottom) hide)
    )
    (property "License" "Apache-2.0" (at 121.285 261.62 0)
      (effects (font (size 1.27 1.27) (thickness 0.15)) (justify left bottom) hide)
    )
    (pin "1")
    (pin "2")
    (pin "3")
    (pin "4")
    (instances
      (project "data-center-rdimm-ddr4-tester"
        (path ""
          (reference "U1") (unit 1)
        )
      )
    )
  )

  (symbol (lib_id "antmicroMicrocontrollers:XC7K160T-FFG676") (at 259.08 59.69 0) (unit 7)
    (in_bom yes) (on_board yes) (dnp no) (fields_autoplaced)
    (property "Reference" "U15" (at 281.94 51.435 0)
      (effects (font (size 1.27 1.27)))
    )
    (property "Value" "XC7K160T-FFG676" (at 281.94 53.975 0)
      (effects (font (size 1.27 1.27) (thickness 0.15)))
    )
    (property "Footprint" "antmicro-footprints:BGA-676_27x27mm_Layout26x26_P1X1mm" (at 327.66 62.23 0)
      (effects (font (size 1.27 1.27) (thickness 0.15)) (justify left bottom) hide)
    )
    (property "Datasheet" "https://docs.xilinx.com/v/u/en-US/ds180_7Series_Overview" (at 327.66 64.77 0)
      (effects (font (size 1.27 1.27) (thickness 0.15)) (justify left bottom) hide)
    )
    (property "MPN" "XC7K160T-FFG676" (at 259.08 59.69 0)
      (effects (font (size 1.27 1.27)) hide)
    )
    (property "Author" "Antmicro" (at 327.66 67.31 0)
      (effects (font (size 1.27 1.27) (thickness 0.15)) (justify left bottom) hide)
    )
    (property "License" "Apache-2.0" (at 327.66 69.85 0)
      (effects (font (size 1.27 1.27) (thickness 0.15)) (justify left bottom) hide)
    )
    (property "Manufacturer" "AMD-Xilinx" (at 259.08 59.69 0)
      (effects (font (size 1.27 1.27)) hide)
    )
    (pin "AA21")
    (pin "AA22")
    (pin "AA23")
    (pin "AA24")
    (pin "AA25")
    (pin "AB21")
    (pin "AB22")
    (pin "AB24")
    (pin "AB25")
    (pin "AB26")
    (pin "AC21")
    (pin "AC22")
    (pin "AC23")
    (pin "AC24")
    (pin "AC25")
    (pin "AC26")
    (pin "AD21")
    (pin "AD22")
    (pin "AD23")
    (pin "AD24")
    (pin "AD25")
    (pin "AD26")
    (pin "AE21")
    (pin "AE22")
    (pin "AE23")
    (pin "AE25")
    (pin "AE26")
    (pin "AF22")
    (pin "AF23")
    (pin "AF24")
    (pin "AF25")
    (pin "AF26")
    (pin "U21")
    (pin "U22")
    (pin "U23")
    (pin "U24")
    (pin "U25")
    (pin "U26")
    (pin "V20")
    (pin "V21")
    (pin "V22")
    (pin "V23")
    (pin "V24")
    (pin "V26")
    (pin "W20")
    (pin "W21")
    (pin "W23")
    (pin "W24")
    (pin "W25")
    (pin "W26")
    (pin "Y20")
    (pin "Y21")
    (pin "Y22")
    (pin "Y23")
    (pin "Y24")
    (pin "Y25")
    (pin "Y26")
    (pin "K24")
    (pin "K25")
    (pin "K26")
    (pin "L24")
    (pin "L25")
    (pin "M19")
    (pin "M20")
    (pin "M21")
    (pin "M22")
    (pin "M24")
    (pin "M25")
    (pin "M26")
    (pin "N16")
    (pin "N17")
    (pin "N18")
    (pin "N19")
    (pin "N21")
    (pin "N22")
    (pin "N23")
    (pin "N24")
    (pin "N25")
    (pin "N26")
    (pin "P16")
    (pin "P18")
    (pin "P19")
    (pin "P20")
    (pin "P21")
    (pin "P22")
    (pin "P23")
    (pin "P24")
    (pin "P25")
    (pin "P26")
    (pin "R16")
    (pin "R17")
    (pin "R18")
    (pin "R19")
    (pin "R20")
    (pin "R21")
    (pin "R22")
    (pin "R23")
    (pin "R25")
    (pin "R26")
    (pin "T16")
    (pin "T17")
    (pin "T18")
    (pin "T19")
    (pin "T20")
    (pin "T22")
    (pin "T23")
    (pin "T24")
    (pin "T25")
    (pin "T26")
    (pin "U16")
    (pin "U17")
    (pin "U19")
    (pin "U20")
    (pin "A20")
    (pin "A21")
    (pin "A22")
    (pin "A23")
    (pin "A24")
    (pin "A25")
    (pin "B20")
    (pin "B21")
    (pin "B22")
    (pin "B24")
    (pin "B25")
    (pin "B26")
    (pin "C21")
    (pin "C22")
    (pin "C23")
    (pin "C24")
    (pin "C25")
    (pin "C26")
    (pin "D21")
    (pin "D22")
    (pin "D23")
    (pin "D24")
    (pin "D25")
    (pin "D26")
    (pin "E21")
    (pin "E22")
    (pin "E23")
    (pin "E25")
    (pin "E26")
    (pin "F22")
    (pin "F23")
    (pin "F24")
    (pin "F25")
    (pin "F26")
    (pin "G21")
    (pin "G22")
    (pin "G23")
    (pin "G24")
    (pin "G25")
    (pin "G26")
    (pin "H21")
    (pin "H22")
    (pin "H23")
    (pin "H24")
    (pin "H26")
    (pin "J21")
    (pin "J23")
    (pin "J24")
    (pin "J25")
    (pin "J26")
    (pin "K21")
    (pin "K22")
    (pin "K23")
    (pin "L21")
    (pin "L22")
    (pin "L23")
    (pin "A17")
    (pin "A18")
    (pin "A19")
    (pin "B16")
    (pin "B17")
    (pin "B18")
    (pin "B19")
    (pin "C16")
    (pin "C17")
    (pin "C18")
    (pin "C19")
    (pin "D15")
    (pin "D16")
    (pin "D18")
    (pin "D19")
    (pin "D20")
    (pin "E15")
    (pin "E16")
    (pin "E17")
    (pin "E18")
    (pin "E19")
    (pin "E20")
    (pin "F15")
    (pin "F16")
    (pin "F17")
    (pin "F18")
    (pin "F19")
    (pin "F20")
    (pin "G15")
    (pin "G16")
    (pin "G17")
    (pin "G19")
    (pin "G20")
    (pin "H16")
    (pin "H17")
    (pin "H18")
    (pin "H19")
    (pin "H20")
    (pin "J15")
    (pin "J16")
    (pin "J17")
    (pin "J18")
    (pin "J19")
    (pin "J20")
    (pin "K15")
    (pin "K16")
    (pin "K17")
    (pin "K18")
    (pin "K20")
    (pin "L17")
    (pin "L18")
    (pin "L19")
    (pin "L20")
    (pin "M16")
    (pin "M17")
    (pin "M18")
    (pin "A10")
    (pin "A11")
    (pin "A12")
    (pin "A13")
    (pin "A14")
    (pin "A15")
    (pin "A8")
    (pin "A9")
    (pin "B10")
    (pin "B11")
    (pin "B12")
    (pin "B14")
    (pin "B15")
    (pin "B8")
    (pin "B9")
    (pin "C11")
    (pin "C12")
    (pin "C13")
    (pin "C14")
    (pin "C15")
    (pin "C9")
    (pin "D10")
    (pin "D11")
    (pin "D12")
    (pin "D13")
    (pin "D14")
    (pin "D8")
    (pin "D9")
    (pin "E10")
    (pin "E11")
    (pin "E12")
    (pin "E13")
    (pin "E9")
    (pin "F10")
    (pin "F12")
    (pin "F13")
    (pin "F14")
    (pin "F8")
    (pin "F9")
    (pin "G10")
    (pin "G11")
    (pin "G12")
    (pin "G13")
    (pin "G14")
    (pin "G9")
    (pin "H10")
    (pin "H11")
    (pin "H12")
    (pin "H13")
    (pin "H14")
    (pin "H8")
    (pin "H9")
    (pin "J10")
    (pin "J11")
    (pin "J13")
    (pin "J14")
    (pin "J8")
    (pin "AA14")
    (pin "AA15")
    (pin "AA17")
    (pin "AA18")
    (pin "AA19")
    (pin "AA20")
    (pin "AB14")
    (pin "AB15")
    (pin "AB16")
    (pin "AB17")
    (pin "AB18")
    (pin "AB19")
    (pin "AB20")
    (pin "AC14")
    (pin "AC15")
    (pin "AC16")
    (pin "AC17")
    (pin "AC18")
    (pin "AC19")
    (pin "AD14")
    (pin "AD15")
    (pin "AD16")
    (pin "AD18")
    (pin "AD19")
    (pin "AD20")
    (pin "AE15")
    (pin "AE16")
    (pin "AE17")
    (pin "AE18")
    (pin "AE19")
    (pin "AE20")
    (pin "AF14")
    (pin "AF15")
    (pin "AF16")
    (pin "AF17")
    (pin "AF18")
    (pin "AF19")
    (pin "AF20")
    (pin "V13")
    (pin "V14")
    (pin "V16")
    (pin "V17")
    (pin "V18")
    (pin "V19")
    (pin "W13")
    (pin "W14")
    (pin "W15")
    (pin "W16")
    (pin "W17")
    (pin "W18")
    (pin "W19")
    (pin "Y14")
    (pin "Y15")
    (pin "Y16")
    (pin "Y17")
    (pin "Y18")
    (pin "AA10")
    (pin "AA11")
    (pin "AA12")
    (pin "AA13")
    (pin "AA7")
    (pin "AA8")
    (pin "AA9")
    (pin "AB10")
    (pin "AB11")
    (pin "AB12")
    (pin "AB7")
    (pin "AB8")
    (pin "AB9")
    (pin "AC11")
    (pin "AC12")
    (pin "AC13")
    (pin "AC7")
    (pin "AC8")
    (pin "AC9")
    (pin "AD10")
    (pin "AD11")
    (pin "AD12")
    (pin "AD13")
    (pin "AD8")
    (pin "AD9")
    (pin "AE10")
    (pin "AE11")
    (pin "AE12")
    (pin "AE13")
    (pin "AE7")
    (pin "AE8")
    (pin "AE9")
    (pin "AF10")
    (pin "AF12")
    (pin "AF13")
    (pin "AF7")
    (pin "AF8")
    (pin "AF9")
    (pin "U9")
    (pin "V10")
    (pin "V11")
    (pin "V12")
    (pin "V7")
    (pin "V8")
    (pin "V9")
    (pin "W10")
    (pin "W11")
    (pin "W7")
    (pin "W8")
    (pin "W9")
    (pin "Y10")
    (pin "Y11")
    (pin "Y12")
    (pin "Y13")
    (pin "Y7")
    (pin "Y8")
    (pin "AA1")
    (pin "AA2")
    (pin "AA3")
    (pin "AA4")
    (pin "AA5")
    (pin "AB1")
    (pin "AB2")
    (pin "AB4")
    (pin "AB5")
    (pin "AB6")
    (pin "AC1")
    (pin "AC2")
    (pin "AC3")
    (pin "AC4")
    (pin "AC5")
    (pin "AC6")
    (pin "AD1")
    (pin "AD2")
    (pin "AD3")
    (pin "AD4")
    (pin "AD5")
    (pin "AD6")
    (pin "AE1")
    (pin "AE2")
    (pin "AE3")
    (pin "AE5")
    (pin "AE6")
    (pin "AF2")
    (pin "AF3")
    (pin "AF4")
    (pin "AF5")
    (pin "AF6")
    (pin "T7")
    (pin "U1")
    (pin "U2")
    (pin "U3")
    (pin "U4")
    (pin "U5")
    (pin "U6")
    (pin "U7")
    (pin "V1")
    (pin "V2")
    (pin "V3")
    (pin "V4")
    (pin "V6")
    (pin "W1")
    (pin "W3")
    (pin "W4")
    (pin "W5")
    (pin "W6")
    (pin "Y1")
    (pin "Y2")
    (pin "Y3")
    (pin "Y4")
    (pin "Y5")
    (pin "Y6")
    (pin "A3")
    (pin "A4")
    (pin "B1")
    (pin "B2")
    (pin "B5")
    (pin "B6")
    (pin "C3")
    (pin "C4")
    (pin "D1")
    (pin "D2")
    (pin "D5")
    (pin "D6")
    (pin "E3")
    (pin "E4")
    (pin "F1")
    (pin "F2")
    (pin "F5")
    (pin "F6")
    (pin "G3")
    (pin "G4")
    (pin "H1")
    (pin "H2")
    (pin "H5")
    (pin "H6")
    (pin "J3")
    (pin "J4")
    (pin "K1")
    (pin "K2")
    (pin "K5")
    (pin "K6")
    (pin "L3")
    (pin "L4")
    (pin "M1")
    (pin "M2")
    (pin "N3")
    (pin "N4")
    (pin "P1")
    (pin "P2")
    (pin "R3")
    (pin "R4")
    (pin "A1")
    (pin "A16")
    (pin "A2")
    (pin "A26")
    (pin "A5")
    (pin "A6")
    (pin "A7")
    (pin "AA16")
    (pin "AA26")
    (pin "AA6")
    (pin "AB13")
    (pin "AB23")
    (pin "AB3")
    (pin "AC10")
    (pin "AC20")
    (pin "AD17")
    (pin "AD7")
    (pin "AE14")
    (pin "AE24")
    (pin "AE4")
    (pin "AF1")
    (pin "AF11")
    (pin "AF21")
    (pin "B13")
    (pin "B23")
    (pin "B3")
    (pin "B4")
    (pin "B7")
    (pin "C1")
    (pin "C10")
    (pin "C2")
    (pin "C20")
    (pin "C5")
    (pin "C6")
    (pin "C7")
    (pin "D17")
    (pin "D3")
    (pin "D4")
    (pin "D7")
    (pin "E1")
    (pin "E14")
    (pin "E2")
    (pin "E24")
    (pin "E5")
    (pin "E6")
    (pin "E7")
    (pin "E8")
    (pin "F11")
    (pin "F21")
    (pin "F3")
    (pin "F4")
    (pin "F7")
    (pin "G1")
    (pin "G18")
    (pin "G2")
    (pin "G5")
    (pin "G6")
    (pin "G8")
    (pin "H15")
    (pin "H25")
    (pin "H3")
    (pin "H4")
    (pin "H7")
    (pin "J1")
    (pin "J12")
    (pin "J2")
    (pin "J22")
    (pin "J5")
    (pin "J6")
    (pin "J9")
    (pin "K10")
    (pin "K11")
    (pin "K12")
    (pin "K13")
    (pin "K14")
    (pin "K19")
    (pin "K3")
    (pin "K4")
    (pin "K7")
    (pin "K8")
    (pin "K9")
    (pin "L1")
    (pin "L10")
    (pin "L11")
    (pin "L12")
    (pin "L13")
    (pin "L14")
    (pin "L15")
    (pin "L16")
    (pin "L2")
    (pin "L26")
    (pin "L5")
    (pin "L6")
    (pin "L9")
    (pin "M10")
    (pin "M11")
    (pin "M12")
    (pin "M13")
    (pin "M14")
    (pin "M15")
    (pin "M23")
    (pin "M3")
    (pin "M4")
    (pin "M5")
    (pin "M6")
    (pin "M7")
    (pin "M8")
    (pin "M9")
    (pin "N1")
    (pin "N10")
    (pin "N13")
    (pin "N14")
    (pin "N15")
    (pin "N2")
    (pin "N20")
    (pin "N5")
    (pin "N6")
    (pin "N7")
    (pin "N9")
    (pin "P10")
    (pin "P13")
    (pin "P14")
    (pin "P15")
    (pin "P17")
    (pin "P3")
    (pin "P4")
    (pin "P8")
    (pin "P9")
    (pin "R1")
    (pin "R10")
    (pin "R13")
    (pin "R14")
    (pin "R15")
    (pin "R2")
    (pin "R24")
    (pin "R5")
    (pin "R8")
    (pin "R9")
    (pin "T1")
    (pin "T10")
    (pin "T11")
    (pin "T12")
    (pin "T13")
    (pin "T14")
    (pin "T15")
    (pin "T21")
    (pin "T3")
    (pin "T4")
    (pin "T8")
    (pin "T9")
    (pin "U10")
    (pin "U11")
    (pin "U12")
    (pin "U13")
    (pin "U14")
    (pin "U15")
    (pin "U18")
    (pin "U8")
    (pin "V15")
    (pin "V25")
    (pin "V5")
    (pin "W12")
    (pin "W2")
    (pin "W22")
    (pin "Y19")
    (pin "Y9")
    (pin "C8")
    (pin "G7")
    (pin "J7")
    (pin "L7")
    (pin "L8")
    (pin "N11")
    (pin "N12")
    (pin "N8")
    (pin "P11")
    (pin "P12")
    (pin "P5")
    (pin "P6")
    (pin "P7")
    (pin "R11")
    (pin "R12")
    (pin "R6")
    (pin "R7")
    (pin "T2")
    (pin "T5")
    (pin "T6")
    (instances
      (project "data-center-rdimm-ddr4-tester"
        (path ""
          (reference "U15") (unit 7)
        )
      )
    )
  )

  (symbol (lib_id "antmicroResistors0603:R_80R6_0603") (at 379.73 241.3 0) (unit 1)
    (in_bom yes) (on_board yes) (dnp no)
    (property "Reference" "R64" (at 382.27 236.22 0)
      (effects (font (size 1.524 1.524)))
    )
    (property "Value" "R_80R6_0603" (at 400.05 254 0)
      (effects (font (size 1.27 1.27) (thickness 0.15)) (justify left bottom) hide)
    )
    (property "Footprint" "antmicro-footprints:R_0603_1608Metric" (at 400.05 256.54 0)
      (effects (font (size 1.27 1.27) (thickness 0.15)) (justify left bottom) hide)
    )
    (property "Datasheet" "https://www.bourns.com/docs/product-datasheets/cr.pdf" (at 400.05 259.08 0)
      (effects (font (size 1.27 1.27) (thickness 0.15)) (justify left bottom) hide)
    )
    (property "Manufacturer" "Bourns" (at 400.05 264.16 0)
      (effects (font (size 1.27 1.27) (thickness 0.15)) (justify left bottom) hide)
    )
    (property "MPN" "CR0603-FX-80R6ELF" (at 400.05 261.62 0)
      (effects (font (size 1.27 1.27) (thickness 0.15)) (justify left bottom) hide)
    )
    (property "Val" "80R6" (at 382.27 238.76 0)
      (effects (font (size 1.27 1.27) (thickness 0.15)))
    )
    (property "License" "Apache-2.0" (at 400.05 266.7 0)
      (effects (font (size 1.27 1.27) (thickness 0.15)) (justify left bottom) hide)
    )
    (property "Author" "Antmicro" (at 400.05 269.24 0)
      (effects (font (size 1.27 1.27) (thickness 0.15)) (justify left bottom) hide)
    )
    (property "Tolerance" "1%" (at 400.05 251.46 0)
      (effects (font (size 1.27 1.27)) (justify left bottom) hide)
    )
    (pin "1")
    (pin "2")
    (instances
      (project "data-center-rdimm-ddr4-tester"
        (path ""
          (reference "R64") (unit 1)
        )
      )
    )
  )

  (symbol (lib_id "antmicroMicrocontrollers:XC7K160T-FFG676") (at 328.93 59.69 0) (unit 8)
    (in_bom yes) (on_board yes) (dnp no) (fields_autoplaced)
    (property "Reference" "U15" (at 351.79 51.435 0)
      (effects (font (size 1.27 1.27)))
    )
    (property "Value" "XC7K160T-FFG676" (at 351.79 53.975 0)
      (effects (font (size 1.27 1.27) (thickness 0.15)))
    )
    (property "Footprint" "antmicro-footprints:BGA-676_27x27mm_Layout26x26_P1X1mm" (at 397.51 62.23 0)
      (effects (font (size 1.27 1.27) (thickness 0.15)) (justify left bottom) hide)
    )
    (property "Datasheet" "https://docs.xilinx.com/v/u/en-US/ds180_7Series_Overview" (at 397.51 64.77 0)
      (effects (font (size 1.27 1.27) (thickness 0.15)) (justify left bottom) hide)
    )
    (property "MPN" "XC7K160T-FFG676" (at 328.93 59.69 0)
      (effects (font (size 1.27 1.27)) hide)
    )
    (property "Author" "Antmicro" (at 397.51 67.31 0)
      (effects (font (size 1.27 1.27) (thickness 0.15)) (justify left bottom) hide)
    )
    (property "License" "Apache-2.0" (at 397.51 69.85 0)
      (effects (font (size 1.27 1.27) (thickness 0.15)) (justify left bottom) hide)
    )
    (property "Manufacturer" "AMD-Xilinx" (at 328.93 59.69 0)
      (effects (font (size 1.27 1.27)) hide)
    )
    (pin "AA21")
    (pin "AA22")
    (pin "AA23")
    (pin "AA24")
    (pin "AA25")
    (pin "AB21")
    (pin "AB22")
    (pin "AB24")
    (pin "AB25")
    (pin "AB26")
    (pin "AC21")
    (pin "AC22")
    (pin "AC23")
    (pin "AC24")
    (pin "AC25")
    (pin "AC26")
    (pin "AD21")
    (pin "AD22")
    (pin "AD23")
    (pin "AD24")
    (pin "AD25")
    (pin "AD26")
    (pin "AE21")
    (pin "AE22")
    (pin "AE23")
    (pin "AE25")
    (pin "AE26")
    (pin "AF22")
    (pin "AF23")
    (pin "AF24")
    (pin "AF25")
    (pin "AF26")
    (pin "U21")
    (pin "U22")
    (pin "U23")
    (pin "U24")
    (pin "U25")
    (pin "U26")
    (pin "V20")
    (pin "V21")
    (pin "V22")
    (pin "V23")
    (pin "V24")
    (pin "V26")
    (pin "W20")
    (pin "W21")
    (pin "W23")
    (pin "W24")
    (pin "W25")
    (pin "W26")
    (pin "Y20")
    (pin "Y21")
    (pin "Y22")
    (pin "Y23")
    (pin "Y24")
    (pin "Y25")
    (pin "Y26")
    (pin "K24")
    (pin "K25")
    (pin "K26")
    (pin "L24")
    (pin "L25")
    (pin "M19")
    (pin "M20")
    (pin "M21")
    (pin "M22")
    (pin "M24")
    (pin "M25")
    (pin "M26")
    (pin "N16")
    (pin "N17")
    (pin "N18")
    (pin "N19")
    (pin "N21")
    (pin "N22")
    (pin "N23")
    (pin "N24")
    (pin "N25")
    (pin "N26")
    (pin "P16")
    (pin "P18")
    (pin "P19")
    (pin "P20")
    (pin "P21")
    (pin "P22")
    (pin "P23")
    (pin "P24")
    (pin "P25")
    (pin "P26")
    (pin "R16")
    (pin "R17")
    (pin "R18")
    (pin "R19")
    (pin "R20")
    (pin "R21")
    (pin "R22")
    (pin "R23")
    (pin "R25")
    (pin "R26")
    (pin "T16")
    (pin "T17")
    (pin "T18")
    (pin "T19")
    (pin "T20")
    (pin "T22")
    (pin "T23")
    (pin "T24")
    (pin "T25")
    (pin "T26")
    (pin "U16")
    (pin "U17")
    (pin "U19")
    (pin "U20")
    (pin "A20")
    (pin "A21")
    (pin "A22")
    (pin "A23")
    (pin "A24")
    (pin "A25")
    (pin "B20")
    (pin "B21")
    (pin "B22")
    (pin "B24")
    (pin "B25")
    (pin "B26")
    (pin "C21")
    (pin "C22")
    (pin "C23")
    (pin "C24")
    (pin "C25")
    (pin "C26")
    (pin "D21")
    (pin "D22")
    (pin "D23")
    (pin "D24")
    (pin "D25")
    (pin "D26")
    (pin "E21")
    (pin "E22")
    (pin "E23")
    (pin "E25")
    (pin "E26")
    (pin "F22")
    (pin "F23")
    (pin "F24")
    (pin "F25")
    (pin "F26")
    (pin "G21")
    (pin "G22")
    (pin "G23")
    (pin "G24")
    (pin "G25")
    (pin "G26")
    (pin "H21")
    (pin "H22")
    (pin "H23")
    (pin "H24")
    (pin "H26")
    (pin "J21")
    (pin "J23")
    (pin "J24")
    (pin "J25")
    (pin "J26")
    (pin "K21")
    (pin "K22")
    (pin "K23")
    (pin "L21")
    (pin "L22")
    (pin "L23")
    (pin "A17")
    (pin "A18")
    (pin "A19")
    (pin "B16")
    (pin "B17")
    (pin "B18")
    (pin "B19")
    (pin "C16")
    (pin "C17")
    (pin "C18")
    (pin "C19")
    (pin "D15")
    (pin "D16")
    (pin "D18")
    (pin "D19")
    (pin "D20")
    (pin "E15")
    (pin "E16")
    (pin "E17")
    (pin "E18")
    (pin "E19")
    (pin "E20")
    (pin "F15")
    (pin "F16")
    (pin "F17")
    (pin "F18")
    (pin "F19")
    (pin "F20")
    (pin "G15")
    (pin "G16")
    (pin "G17")
    (pin "G19")
    (pin "G20")
    (pin "H16")
    (pin "H17")
    (pin "H18")
    (pin "H19")
    (pin "H20")
    (pin "J15")
    (pin "J16")
    (pin "J17")
    (pin "J18")
    (pin "J19")
    (pin "J20")
    (pin "K15")
    (pin "K16")
    (pin "K17")
    (pin "K18")
    (pin "K20")
    (pin "L17")
    (pin "L18")
    (pin "L19")
    (pin "L20")
    (pin "M16")
    (pin "M17")
    (pin "M18")
    (pin "A10")
    (pin "A11")
    (pin "A12")
    (pin "A13")
    (pin "A14")
    (pin "A15")
    (pin "A8")
    (pin "A9")
    (pin "B10")
    (pin "B11")
    (pin "B12")
    (pin "B14")
    (pin "B15")
    (pin "B8")
    (pin "B9")
    (pin "C11")
    (pin "C12")
    (pin "C13")
    (pin "C14")
    (pin "C15")
    (pin "C9")
    (pin "D10")
    (pin "D11")
    (pin "D12")
    (pin "D13")
    (pin "D14")
    (pin "D8")
    (pin "D9")
    (pin "E10")
    (pin "E11")
    (pin "E12")
    (pin "E13")
    (pin "E9")
    (pin "F10")
    (pin "F12")
    (pin "F13")
    (pin "F14")
    (pin "F8")
    (pin "F9")
    (pin "G10")
    (pin "G11")
    (pin "G12")
    (pin "G13")
    (pin "G14")
    (pin "G9")
    (pin "H10")
    (pin "H11")
    (pin "H12")
    (pin "H13")
    (pin "H14")
    (pin "H8")
    (pin "H9")
    (pin "J10")
    (pin "J11")
    (pin "J13")
    (pin "J14")
    (pin "J8")
    (pin "AA14")
    (pin "AA15")
    (pin "AA17")
    (pin "AA18")
    (pin "AA19")
    (pin "AA20")
    (pin "AB14")
    (pin "AB15")
    (pin "AB16")
    (pin "AB17")
    (pin "AB18")
    (pin "AB19")
    (pin "AB20")
    (pin "AC14")
    (pin "AC15")
    (pin "AC16")
    (pin "AC17")
    (pin "AC18")
    (pin "AC19")
    (pin "AD14")
    (pin "AD15")
    (pin "AD16")
    (pin "AD18")
    (pin "AD19")
    (pin "AD20")
    (pin "AE15")
    (pin "AE16")
    (pin "AE17")
    (pin "AE18")
    (pin "AE19")
    (pin "AE20")
    (pin "AF14")
    (pin "AF15")
    (pin "AF16")
    (pin "AF17")
    (pin "AF18")
    (pin "AF19")
    (pin "AF20")
    (pin "V13")
    (pin "V14")
    (pin "V16")
    (pin "V17")
    (pin "V18")
    (pin "V19")
    (pin "W13")
    (pin "W14")
    (pin "W15")
    (pin "W16")
    (pin "W17")
    (pin "W18")
    (pin "W19")
    (pin "Y14")
    (pin "Y15")
    (pin "Y16")
    (pin "Y17")
    (pin "Y18")
    (pin "AA10")
    (pin "AA11")
    (pin "AA12")
    (pin "AA13")
    (pin "AA7")
    (pin "AA8")
    (pin "AA9")
    (pin "AB10")
    (pin "AB11")
    (pin "AB12")
    (pin "AB7")
    (pin "AB8")
    (pin "AB9")
    (pin "AC11")
    (pin "AC12")
    (pin "AC13")
    (pin "AC7")
    (pin "AC8")
    (pin "AC9")
    (pin "AD10")
    (pin "AD11")
    (pin "AD12")
    (pin "AD13")
    (pin "AD8")
    (pin "AD9")
    (pin "AE10")
    (pin "AE11")
    (pin "AE12")
    (pin "AE13")
    (pin "AE7")
    (pin "AE8")
    (pin "AE9")
    (pin "AF10")
    (pin "AF12")
    (pin "AF13")
    (pin "AF7")
    (pin "AF8")
    (pin "AF9")
    (pin "U9")
    (pin "V10")
    (pin "V11")
    (pin "V12")
    (pin "V7")
    (pin "V8")
    (pin "V9")
    (pin "W10")
    (pin "W11")
    (pin "W7")
    (pin "W8")
    (pin "W9")
    (pin "Y10")
    (pin "Y11")
    (pin "Y12")
    (pin "Y13")
    (pin "Y7")
    (pin "Y8")
    (pin "AA1")
    (pin "AA2")
    (pin "AA3")
    (pin "AA4")
    (pin "AA5")
    (pin "AB1")
    (pin "AB2")
    (pin "AB4")
    (pin "AB5")
    (pin "AB6")
    (pin "AC1")
    (pin "AC2")
    (pin "AC3")
    (pin "AC4")
    (pin "AC5")
    (pin "AC6")
    (pin "AD1")
    (pin "AD2")
    (pin "AD3")
    (pin "AD4")
    (pin "AD5")
    (pin "AD6")
    (pin "AE1")
    (pin "AE2")
    (pin "AE3")
    (pin "AE5")
    (pin "AE6")
    (pin "AF2")
    (pin "AF3")
    (pin "AF4")
    (pin "AF5")
    (pin "AF6")
    (pin "T7")
    (pin "U1")
    (pin "U2")
    (pin "U3")
    (pin "U4")
    (pin "U5")
    (pin "U6")
    (pin "U7")
    (pin "V1")
    (pin "V2")
    (pin "V3")
    (pin "V4")
    (pin "V6")
    (pin "W1")
    (pin "W3")
    (pin "W4")
    (pin "W5")
    (pin "W6")
    (pin "Y1")
    (pin "Y2")
    (pin "Y3")
    (pin "Y4")
    (pin "Y5")
    (pin "Y6")
    (pin "A3")
    (pin "A4")
    (pin "B1")
    (pin "B2")
    (pin "B5")
    (pin "B6")
    (pin "C3")
    (pin "C4")
    (pin "D1")
    (pin "D2")
    (pin "D5")
    (pin "D6")
    (pin "E3")
    (pin "E4")
    (pin "F1")
    (pin "F2")
    (pin "F5")
    (pin "F6")
    (pin "G3")
    (pin "G4")
    (pin "H1")
    (pin "H2")
    (pin "H5")
    (pin "H6")
    (pin "J3")
    (pin "J4")
    (pin "K1")
    (pin "K2")
    (pin "K5")
    (pin "K6")
    (pin "L3")
    (pin "L4")
    (pin "M1")
    (pin "M2")
    (pin "N3")
    (pin "N4")
    (pin "P1")
    (pin "P2")
    (pin "R3")
    (pin "R4")
    (pin "A1")
    (pin "A16")
    (pin "A2")
    (pin "A26")
    (pin "A5")
    (pin "A6")
    (pin "A7")
    (pin "AA16")
    (pin "AA26")
    (pin "AA6")
    (pin "AB13")
    (pin "AB23")
    (pin "AB3")
    (pin "AC10")
    (pin "AC20")
    (pin "AD17")
    (pin "AD7")
    (pin "AE14")
    (pin "AE24")
    (pin "AE4")
    (pin "AF1")
    (pin "AF11")
    (pin "AF21")
    (pin "B13")
    (pin "B23")
    (pin "B3")
    (pin "B4")
    (pin "B7")
    (pin "C1")
    (pin "C10")
    (pin "C2")
    (pin "C20")
    (pin "C5")
    (pin "C6")
    (pin "C7")
    (pin "D17")
    (pin "D3")
    (pin "D4")
    (pin "D7")
    (pin "E1")
    (pin "E14")
    (pin "E2")
    (pin "E24")
    (pin "E5")
    (pin "E6")
    (pin "E7")
    (pin "E8")
    (pin "F11")
    (pin "F21")
    (pin "F3")
    (pin "F4")
    (pin "F7")
    (pin "G1")
    (pin "G18")
    (pin "G2")
    (pin "G5")
    (pin "G6")
    (pin "G8")
    (pin "H15")
    (pin "H25")
    (pin "H3")
    (pin "H4")
    (pin "H7")
    (pin "J1")
    (pin "J12")
    (pin "J2")
    (pin "J22")
    (pin "J5")
    (pin "J6")
    (pin "J9")
    (pin "K10")
    (pin "K11")
    (pin "K12")
    (pin "K13")
    (pin "K14")
    (pin "K19")
    (pin "K3")
    (pin "K4")
    (pin "K7")
    (pin "K8")
    (pin "K9")
    (pin "L1")
    (pin "L10")
    (pin "L11")
    (pin "L12")
    (pin "L13")
    (pin "L14")
    (pin "L15")
    (pin "L16")
    (pin "L2")
    (pin "L26")
    (pin "L5")
    (pin "L6")
    (pin "L9")
    (pin "M10")
    (pin "M11")
    (pin "M12")
    (pin "M13")
    (pin "M14")
    (pin "M15")
    (pin "M23")
    (pin "M3")
    (pin "M4")
    (pin "M5")
    (pin "M6")
    (pin "M7")
    (pin "M8")
    (pin "M9")
    (pin "N1")
    (pin "N10")
    (pin "N13")
    (pin "N14")
    (pin "N15")
    (pin "N2")
    (pin "N20")
    (pin "N5")
    (pin "N6")
    (pin "N7")
    (pin "N9")
    (pin "P10")
    (pin "P13")
    (pin "P14")
    (pin "P15")
    (pin "P17")
    (pin "P3")
    (pin "P4")
    (pin "P8")
    (pin "P9")
    (pin "R1")
    (pin "R10")
    (pin "R13")
    (pin "R14")
    (pin "R15")
    (pin "R2")
    (pin "R24")
    (pin "R5")
    (pin "R8")
    (pin "R9")
    (pin "T1")
    (pin "T10")
    (pin "T11")
    (pin "T12")
    (pin "T13")
    (pin "T14")
    (pin "T15")
    (pin "T21")
    (pin "T3")
    (pin "T4")
    (pin "T8")
    (pin "T9")
    (pin "U10")
    (pin "U11")
    (pin "U12")
    (pin "U13")
    (pin "U14")
    (pin "U15")
    (pin "U18")
    (pin "U8")
    (pin "V15")
    (pin "V25")
    (pin "V5")
    (pin "W12")
    (pin "W2")
    (pin "W22")
    (pin "Y19")
    (pin "Y9")
    (pin "C8")
    (pin "G7")
    (pin "J7")
    (pin "L7")
    (pin "L8")
    (pin "N11")
    (pin "N12")
    (pin "N8")
    (pin "P11")
    (pin "P12")
    (pin "P5")
    (pin "P6")
    (pin "P7")
    (pin "R11")
    (pin "R12")
    (pin "R6")
    (pin "R7")
    (pin "T2")
    (pin "T5")
    (pin "T6")
    (instances
      (project "data-center-rdimm-ddr4-tester"
        (path ""
          (reference "U15") (unit 8)
        )
      )
    )
  )

  (symbol (lib_id "antmicroResistors0603:R_80R6_0603") (at 379.73 233.045 0) (unit 1)
    (in_bom yes) (on_board yes) (dnp no)
    (property "Reference" "R63" (at 382.27 227.965 0)
      (effects (font (size 1.524 1.524)))
    )
    (property "Value" "R_80R6_0603" (at 400.05 245.745 0)
      (effects (font (size 1.27 1.27) (thickness 0.15)) (justify left bottom) hide)
    )
    (property "Footprint" "antmicro-footprints:R_0603_1608Metric" (at 400.05 248.285 0)
      (effects (font (size 1.27 1.27) (thickness 0.15)) (justify left bottom) hide)
    )
    (property "Datasheet" "https://www.bourns.com/docs/product-datasheets/cr.pdf" (at 400.05 250.825 0)
      (effects (font (size 1.27 1.27) (thickness 0.15)) (justify left bottom) hide)
    )
    (property "Manufacturer" "Bourns" (at 400.05 255.905 0)
      (effects (font (size 1.27 1.27) (thickness 0.15)) (justify left bottom) hide)
    )
    (property "MPN" "CR0603-FX-80R6ELF" (at 400.05 253.365 0)
      (effects (font (size 1.27 1.27) (thickness 0.15)) (justify left bottom) hide)
    )
    (property "Val" "80R6" (at 382.27 230.505 0)
      (effects (font (size 1.27 1.27) (thickness 0.15)))
    )
    (property "License" "Apache-2.0" (at 400.05 258.445 0)
      (effects (font (size 1.27 1.27) (thickness 0.15)) (justify left bottom) hide)
    )
    (property "Author" "Antmicro" (at 400.05 260.985 0)
      (effects (font (size 1.27 1.27) (thickness 0.15)) (justify left bottom) hide)
    )
    (property "Tolerance" "1%" (at 400.05 243.205 0)
      (effects (font (size 1.27 1.27)) (justify left bottom) hide)
    )
    (pin "1")
    (pin "2")
    (instances
      (project "data-center-rdimm-ddr4-tester"
        (path ""
          (reference "R63") (unit 1)
        )
      )
    )
  )
)
